FILE_TYPE = MACRO_DRAWING;
SET COLOR_WIRE YELLOW;
SET COLOR_PROP ORANGE;
SET COLOR_DOT WHITE;
SET COLOR_ARC YELLOW;
SET COLOR_BODY GREEN;
SET COLOR_NOTE PURPLE;
SET PROP_DISPLAY VALUE;
SET PAGE_NUMBER P138;
FORCEADD Q_RES..1
(3025 5500);
FORCEPROP 1 LAST LOCATION R326
J 0
(2800 5500);
DISPLAY 0.787234 (2800 5500);
FORCEPROP 0 LAST $SEC 1
J 0
(2850 5550);
DISPLAY 0.680851 (2850 5550);
PAINT MONO (2850 5550);
DISPLAY INVISIBLE (2850 5550);
FORCEPROP 0 LAST CDS_SEC 1
J 0
(2850 5550);
DISPLAY 0.680851 (2850 5550);
DISPLAY INVISIBLE (2850 5550);
FORCEPROP 1 LASTPIN (2925 5500) $PN 1
J 0
(2937 5512);
DISPLAY 0.787234 (2937 5512);
PAINT MONO (2937 5512);
FORCEPROP 1 LASTPIN (3125 5500) $PN 2
J 0
(3087 5512);
DISPLAY 0.787234 (3087 5512);
PAINT MONO (3087 5512);
FORCEPROP 1 LAST VALUE 0
J 2
(3200 5500);
DISPLAY 0.510638 (3200 5500);
FORCEPROP 1 LAST PACK_TYPE 0402LF
J 0
(3375 5500);
DISPLAY 0.510638 (3375 5500);
FORCEPROP 1 LAST MATERIAL CHIP
J 0
(3225 5500);
DISPLAY 0.510638 (3225 5500);
FORCEPROP 1 LAST TOLERANCE 5%
J 0
(3000 5400);
DISPLAY 0.978723 (3000 5400);
DISPLAY INVISIBLE (3000 5400);
FORCEPROP 1 LAST WATTAGE 1/16W
J 2
(3000 5350);
DISPLAY 0.978723 (3000 5350);
DISPLAY INVISIBLE (3000 5350);
FORCEPROP 2 LAST CDS_LIB pure_quanta
J 0
(3025 5500);
DISPLAY INVISIBLE (3025 5500);
FORCEPROP 1 LAST PATH I100
J 0
(2975 5650);
DISPLAY 0.978723 (2975 5650);
PAINT WHITE (2975 5650);
DISPLAY INVISIBLE (2975 5650);
FORCEPROP 1 LAST PART_NUMBER CS00002JB13
J 0
(3150 5525);
DISPLAY 0.978723 (3150 5525);
DISPLAY INVISIBLE (3150 5525);
FORCEADD OFFPAGE..1
(2175 5550);
FORCEPROP 2 LAST $XR1 161 
J 0
(1803 5550);
DISPLAY 0.638298 (1803 5550);
PAINT MONO (1803 5550);
FORCEPROP 2 LAST $XR0 160 
J 0
(1923 5550);
DISPLAY 0.638298 (1923 5550);
PAINT MONO (1923 5550);
FORCEPROP 2 LAST CDS_LIB standard
J 0
(2175 5550);
DISPLAY INVISIBLE (2175 5550);
FORCEPROP 1 LAST OFFPAGE TRUE
J 0
(2500 5425);
DISPLAY 0.872340 (2500 5425);
PAINT GREEN (2500 5425);
DISPLAY INVISIBLE (2500 5425);
FORCEPROP 1 LAST COMMENT_BODY TRUE
J 0
(2300 5450);
DISPLAY 0.872340 (2300 5450);
PAINT GREEN (2300 5450);
DISPLAY INVISIBLE (2300 5450);
FORCEPROP 2 LAST PATH I101
J 0
(2225 5625);
DISPLAY 0.680851 (2225 5625);
DISPLAY INVISIBLE (2225 5625);
FORCEADD OFFPAGE..3
R 2
(2175 5500);
FORCEPROP 2 LAST $XR1 161 
J 0
(1775 5500);
DISPLAY 0.638298 (1775 5500);
PAINT MONO (1775 5500);
FORCEPROP 2 LAST $XR0 160 
J 0
(1895 5500);
DISPLAY 0.638298 (1895 5500);
PAINT MONO (1895 5500);
FORCEPROP 2 LAST CDS_LIB standard
J 0
(2175 5500);
DISPLAY INVISIBLE (2175 5500);
FORCEPROP 1 LAST OFFPAGE TRUE
J 2
(1850 5375);
DISPLAY 0.872340 (1850 5375);
PAINT GREEN (1850 5375);
DISPLAY INVISIBLE (1850 5375);
FORCEPROP 1 LAST COMMENT_BODY TRUE
J 2
(2225 5400);
DISPLAY 0.872340 (2225 5400);
PAINT GREEN (2225 5400);
DISPLAY INVISIBLE (2225 5400);
FORCEPROP 2 LAST PATH I102
J 0
(2225 5575);
DISPLAY 0.680851 (2225 5575);
DISPLAY INVISIBLE (2225 5575);
FORCEADD OFFPAGE..3
R 2
(-1225 3875);
FORCEPROP 2 LAST $XR1 161 
J 0
(-1625 3875);
DISPLAY 0.638298 (-1625 3875);
PAINT MONO (-1625 3875);
FORCEPROP 2 LAST $XR0 160 
J 0
(-1505 3875);
DISPLAY 0.638298 (-1505 3875);
PAINT MONO (-1505 3875);
FORCEPROP 2 LAST CDS_LIB standard
J 0
(-1225 3875);
DISPLAY INVISIBLE (-1225 3875);
FORCEPROP 1 LAST OFFPAGE TRUE
J 2
(-1550 3750);
DISPLAY 0.872340 (-1550 3750);
PAINT GREEN (-1550 3750);
DISPLAY INVISIBLE (-1550 3750);
FORCEPROP 1 LAST COMMENT_BODY TRUE
J 2
(-1175 3775);
DISPLAY 0.872340 (-1175 3775);
PAINT GREEN (-1175 3775);
DISPLAY INVISIBLE (-1175 3775);
FORCEPROP 2 LAST PATH I103
J 0
(-1500 3925);
DISPLAY 0.680851 (-1500 3925);
DISPLAY INVISIBLE (-1500 3925);
FORCEADD OFFPAGE..1
(-1225 3825);
FORCEPROP 2 LAST $XR1 161 
J 0
(-1627 3825);
DISPLAY 0.638298 (-1627 3825);
PAINT MONO (-1627 3825);
FORCEPROP 2 LAST $XR0 160 
J 0
(-1507 3825);
DISPLAY 0.638298 (-1507 3825);
PAINT MONO (-1507 3825);
FORCEPROP 2 LAST CDS_LIB standard
J 0
(-1225 3825);
DISPLAY INVISIBLE (-1225 3825);
FORCEPROP 1 LAST OFFPAGE TRUE
J 0
(-900 3700);
DISPLAY 0.872340 (-900 3700);
PAINT GREEN (-900 3700);
DISPLAY INVISIBLE (-900 3700);
FORCEPROP 1 LAST COMMENT_BODY TRUE
J 0
(-1100 3725);
DISPLAY 0.872340 (-1100 3725);
PAINT GREEN (-1100 3725);
DISPLAY INVISIBLE (-1100 3725);
FORCEPROP 2 LAST PATH I104
J 0
(-1500 3875);
DISPLAY 0.680851 (-1500 3875);
DISPLAY INVISIBLE (-1500 3875);
FORCEADD Q_RES..1
(-575 3875);
FORCEPROP 1 LAST LOCATION R323
J 0
(-650 3925);
DISPLAY 0.978723 (-650 3925);
FORCEPROP 0 LAST $SEC 1
J 0
(-650 3975);
DISPLAY 0.680851 (-650 3975);
PAINT MONO (-650 3975);
DISPLAY INVISIBLE (-650 3975);
FORCEPROP 0 LAST CDS_SEC 1
J 0
(-650 3975);
DISPLAY 0.680851 (-650 3975);
DISPLAY INVISIBLE (-650 3975);
FORCEPROP 1 LASTPIN (-675 3875) $PN 1
J 0
(-663 3887);
DISPLAY 0.787234 (-663 3887);
PAINT MONO (-663 3887);
FORCEPROP 1 LASTPIN (-475 3875) $PN 2
J 0
(-513 3887);
DISPLAY 0.787234 (-513 3887);
PAINT MONO (-513 3887);
FORCEPROP 1 LAST VALUE 0
J 2
(-375 3875);
DISPLAY 0.489362 (-375 3875);
PAINT SKYBLUE (-375 3875);
FORCEPROP 1 LAST MATERIAL EMPTY
J 0
(-300 3875);
DISPLAY 0.489362 (-300 3875);
PAINT RED (-300 3875);
FORCEPROP 1 LAST PACK_TYPE 0402LF
J 0
(-525 3800);
DISPLAY 0.489362 (-525 3800);
PAINT SKYBLUE (-525 3800);
DISPLAY INVISIBLE (-525 3800);
FORCEPROP 1 LAST TOLERANCE 5%
J 0
(-600 3800);
DISPLAY 0.489362 (-600 3800);
PAINT SKYBLUE (-600 3800);
DISPLAY INVISIBLE (-600 3800);
FORCEPROP 1 LAST WATTAGE 1/16W
J 2
(-175 3800);
DISPLAY 0.489362 (-175 3800);
PAINT SKYBLUE (-175 3800);
DISPLAY INVISIBLE (-175 3800);
FORCEPROP 2 LAST CDS_LIB pure_quanta
J 0
(-575 3875);
DISPLAY INVISIBLE (-575 3875);
FORCEPROP 1 LAST PATH I109
J 0
(-625 4025);
DISPLAY 0.978723 (-625 4025);
PAINT WHITE (-625 4025);
DISPLAY INVISIBLE (-625 4025);
FORCEPROP 1 LAST PART_NUMBER CS00002JB13
J 0
(-550 3925);
DISPLAY 0.489362 (-550 3925);
PAINT SKYBLUE (-550 3925);
DISPLAY INVISIBLE (-550 3925);
FORCEADD Q_RES..1
(-575 3825);
FORCEPROP 1 LAST LOCATION R324
J 0
(-675 3750);
DISPLAY 0.978723 (-675 3750);
FORCEPROP 0 LAST $SEC 1
J 0
(-300 3850);
DISPLAY 0.680851 (-300 3850);
PAINT MONO (-300 3850);
DISPLAY INVISIBLE (-300 3850);
FORCEPROP 0 LAST CDS_SEC 1
J 0
(-300 3850);
DISPLAY 0.680851 (-300 3850);
DISPLAY INVISIBLE (-300 3850);
FORCEPROP 1 LASTPIN (-675 3825) $PN 1
J 0
(-663 3837);
DISPLAY 0.787234 (-663 3837);
PAINT MONO (-663 3837);
FORCEPROP 1 LASTPIN (-475 3825) $PN 2
J 0
(-513 3837);
DISPLAY 0.787234 (-513 3837);
PAINT MONO (-513 3837);
FORCEPROP 1 LAST VALUE 0
J 2
(-375 3825);
DISPLAY 0.489362 (-375 3825);
PAINT SKYBLUE (-375 3825);
FORCEPROP 1 LAST MATERIAL EMPTY
J 0
(-300 3825);
DISPLAY 0.489362 (-300 3825);
PAINT RED (-300 3825);
FORCEPROP 1 LAST WATTAGE 1/16W
J 2
(-175 3750);
DISPLAY 0.489362 (-175 3750);
PAINT SKYBLUE (-175 3750);
DISPLAY INVISIBLE (-175 3750);
FORCEPROP 1 LAST TOLERANCE 5%
J 0
(-600 3750);
DISPLAY 0.489362 (-600 3750);
PAINT SKYBLUE (-600 3750);
DISPLAY INVISIBLE (-600 3750);
FORCEPROP 1 LAST PACK_TYPE 0402LF
J 0
(-525 3750);
DISPLAY 0.489362 (-525 3750);
PAINT SKYBLUE (-525 3750);
DISPLAY INVISIBLE (-525 3750);
FORCEPROP 2 LAST CDS_LIB pure_quanta
J 0
(-575 3825);
DISPLAY INVISIBLE (-575 3825);
FORCEPROP 1 LAST PATH I110
J 0
(-625 3975);
DISPLAY 0.978723 (-625 3975);
PAINT WHITE (-625 3975);
DISPLAY INVISIBLE (-625 3975);
FORCEPROP 1 LAST PART_NUMBER CS00002JB13
J 0
(-550 3875);
DISPLAY 0.489362 (-550 3875);
PAINT SKYBLUE (-550 3875);
DISPLAY INVISIBLE (-550 3875);
FORCEADD IML3112Y2B000NCG8..1
(1675 3925);
FORCEPROP 1 LAST LOCATION U213
J 0
(1400 4300);
DISPLAY 0.723404 (1400 4300);
PAINT GREEN (1400 4300);
FORCEPROP 2 LAST SEC 1
J 0
(1425 4600);
DISPLAY 0.680851 (1425 4600);
PAINT MONO (1425 4600);
DISPLAY INVISIBLE (1425 4600);
FORCEPROP 2 LASTPIN (1250 3825) $PN 3
J 2
(1240 3835);
DISPLAY 0.680851 (1240 3835);
PAINT MONO (1240 3835);
FORCEPROP 2 LASTPIN (1250 3875) $PN 2
J 2
(1240 3885);
DISPLAY 0.680851 (1240 3885);
PAINT MONO (1240 3885);
FORCEPROP 2 LASTPIN (2100 3975) $PN 4
J 0
(2110 3985);
DISPLAY 0.680851 (2110 3985);
PAINT MONO (2110 3985);
FORCEPROP 2 LASTPIN (2100 3875) $PN 6
J 0
(2110 3885);
DISPLAY 0.680851 (2110 3885);
PAINT MONO (2110 3885);
FORCEPROP 2 LASTPIN (2100 4025) $PN 1
J 0
(2110 4035);
DISPLAY 0.680851 (2110 4035);
PAINT MONO (2110 4035);
FORCEPROP 2 LASTPIN (2100 3825) $PN 8
J 0
(2110 3835);
DISPLAY 0.680851 (2110 3835);
PAINT MONO (2110 3835);
FORCEPROP 2 LASTPIN (2100 3775) $PN 9
J 0
(2110 3785);
DISPLAY 0.680851 (2110 3785);
PAINT MONO (2110 3785);
FORCEPROP 2 LASTPIN (1250 4125) $PN 5
J 2
(1240 4135);
DISPLAY 0.680851 (1240 4135);
PAINT MONO (1240 4135);
FORCEPROP 2 LASTPIN (1250 4075) $PN 7
J 2
(1240 4085);
DISPLAY 0.680851 (1240 4085);
PAINT MONO (1240 4085);
FORCEPROP 1 LAST MATERIAL EMPTY
J 0
(1405 4186);
DISPLAY 0.723404 (1405 4186);
PAINT RED (1405 4186);
FORCEPROP 2 LAST VALUE IML3112-Y2B000NCG8
J 0
(1400 4350);
DISPLAY 0.680851 (1400 4350);
FORCEPROP 2 LAST PART_TYPE SMLF
J 0
(1400 4400);
DISPLAY 0.680851 (1400 4400);
FORCEPROP 2 LAST CDS_LIB pure_quanta
J 0
(1675 3925);
DISPLAY INVISIBLE (1675 3925);
FORCEPROP 1 LAST NEEDS_NO_SIZE TRUE
J 0
(1675 3925);
DISPLAY 0.723404 (1675 3925);
PAINT GREEN (1675 3925);
DISPLAY INVISIBLE (1675 3925);
FORCEPROP 1 LAST CDS_LMAN_SYM_OUTLINE -275,250,275,-250
J 0
(1675 3925);
DISPLAY 0.468085 (1675 3925);
PAINT GREEN (1675 3925);
DISPLAY INVISIBLE (1675 3925);
FORCEPROP 2 LAST SEC_TYPE 
J 0
(1425 4600);
DISPLAY 0.680851 (1425 4600);
DISPLAY INVISIBLE (1425 4600);
FORCEPROP 1 LAST PATH I111
J 0
(1675 3925);
DISPLAY 0.723404 (1675 3925);
PAINT GREEN (1675 3925);
DISPLAY INVISIBLE (1675 3925);
FORCEPROP 1 LAST PART_NUMBER AL003112004
J 0
(1400 4250);
DISPLAY 0.723404 (1400 4250);
PAINT GREEN (1400 4250);
DISPLAY INVISIBLE (1400 4250);
FORCEADD Q_CAP..1
R 2
(700 4350);
FORCEPROP 1 LAST LOCATION C24
J 2
(650 4450);
DISPLAY 0.638298 (650 4450);
FORCEPROP 0 LAST $SEC 1
J 0
(650 4500);
DISPLAY 0.680851 (650 4500);
PAINT MONO (650 4500);
DISPLAY INVISIBLE (650 4500);
FORCEPROP 0 LAST CDS_SEC 1
J 0
(650 4500);
DISPLAY 0.680851 (650 4500);
DISPLAY INVISIBLE (650 4500);
FORCEPROP 1 LASTPIN (700 4450) $PN 1
J 2
(690 4430);
DISPLAY 0.787234 (690 4430);
PAINT MONO (690 4430);
FORCEPROP 1 LASTPIN (700 4250) $PN 2
J 2
(690 4230);
DISPLAY 0.787234 (690 4230);
PAINT MONO (690 4230);
FORCEPROP 1 LAST PACK_TYPE C0402
J 2
(650 4200);
DISPLAY 0.638298 (650 4200);
FORCEPROP 1 LAST MATERIAL EMPTY
J 2
(650 4250);
DISPLAY 0.638298 (650 4250);
PAINT RED (650 4250);
FORCEPROP 1 LAST VALUE 10UF
J 2
(650 4400);
DISPLAY 0.638298 (650 4400);
FORCEPROP 1 LAST TOLERANCE 20%
J 2
(650 4300);
DISPLAY 0.638298 (650 4300);
FORCEPROP 1 LAST VOLTAGE 6.3V
J 2
(650 4350);
DISPLAY 0.638298 (650 4350);
FORCEPROP 2 LAST CDS_LIB pure_quanta
J 2
(700 4350);
DISPLAY INVISIBLE (700 4350);
FORCEPROP 1 LAST PATH I112
J 2
(650 4500);
DISPLAY 0.978723 (650 4500);
PAINT WHITE (650 4500);
DISPLAY INVISIBLE (650 4500);
FORCEPROP 1 LAST PART_NUMBER CH6101MEB01
J 2
(650 4200);
DISPLAY 0.638298 (650 4200);
DISPLAY INVISIBLE (650 4200);
FORCEADD Q_CAP..1
R 2
(175 4350);
FORCEPROP 1 LAST LOCATION C9
J 2
(125 4450);
DISPLAY 0.638298 (125 4450);
FORCEPROP 0 LAST $SEC 1
J 0
(125 4500);
DISPLAY 0.680851 (125 4500);
PAINT MONO (125 4500);
DISPLAY INVISIBLE (125 4500);
FORCEPROP 0 LAST CDS_SEC 1
J 0
(125 4500);
DISPLAY 0.680851 (125 4500);
DISPLAY INVISIBLE (125 4500);
FORCEPROP 1 LASTPIN (175 4450) $PN 1
J 2
(165 4430);
DISPLAY 0.787234 (165 4430);
PAINT MONO (165 4430);
FORCEPROP 1 LASTPIN (175 4250) $PN 2
J 2
(165 4230);
DISPLAY 0.787234 (165 4230);
PAINT MONO (165 4230);
FORCEPROP 1 LAST VOLTAGE 25V
J 2
(125 4350);
DISPLAY 0.510638 (125 4350);
FORCEPROP 1 LAST PACK_TYPE C0402
J 2
(125 4200);
DISPLAY 0.510638 (125 4200);
FORCEPROP 1 LAST MATERIAL EMPTY
J 2
(125 4250);
DISPLAY 0.510638 (125 4250);
PAINT RED (125 4250);
FORCEPROP 1 LAST TOLERANCE 10%
J 2
(125 4300);
DISPLAY 0.510638 (125 4300);
FORCEPROP 1 LAST VALUE 1UF
J 2
(125 4400);
DISPLAY 0.510638 (125 4400);
FORCEPROP 2 LAST CDS_LIB pure_quanta
J 2
(175 4350);
DISPLAY INVISIBLE (175 4350);
FORCEPROP 1 LAST PATH I113
J 2
(125 4500);
DISPLAY 0.978723 (125 4500);
PAINT WHITE (125 4500);
DISPLAY INVISIBLE (125 4500);
FORCEPROP 1 LAST PART_NUMBER CH5104KEB02
J 2
(125 4200);
DISPLAY 0.978723 (125 4200);
DISPLAY INVISIBLE (125 4200);
FORCEADD PI3CSW12ZUAEX..1
R 2
(4600 5450);
FORCEPROP 1 LAST LOCATION U4
J 2
(4769 5743);
DISPLAY 0.723404 (4769 5743);
PAINT GREEN (4769 5743);
FORCEPROP 2 LAST SEC 1
J 0
(4750 5900);
DISPLAY 0.680851 (4750 5900);
PAINT MONO (4750 5900);
DISPLAY INVISIBLE (4750 5900);
FORCEPROP 2 LASTPIN (4900 5450) $PN 1
J 0
(4910 5460);
DISPLAY 0.680851 (4910 5460);
PAINT MONO (4910 5460);
FORCEPROP 2 LASTPIN (4900 5400) $PN 2
J 0
(4910 5410);
DISPLAY 0.680851 (4910 5410);
PAINT MONO (4910 5410);
FORCEPROP 2 LASTPIN (4900 5350) $PN 3
J 0
(4910 5360);
DISPLAY 0.680851 (4910 5360);
PAINT MONO (4910 5360);
FORCEPROP 2 LASTPIN (4900 5300) $PN 4
J 0
(4910 5310);
DISPLAY 0.680851 (4910 5310);
PAINT MONO (4910 5310);
FORCEPROP 2 LASTPIN (4300 5550) $PN 8
J 2
(4290 5560);
DISPLAY 0.680851 (4290 5560);
PAINT MONO (4290 5560);
FORCEPROP 2 LASTPIN (4300 5500) $PN 7
J 2
(4290 5510);
DISPLAY 0.680851 (4290 5510);
PAINT MONO (4290 5510);
FORCEPROP 2 LASTPIN (4300 5300) $PN 5
J 2
(4290 5310);
DISPLAY 0.680851 (4290 5310);
PAINT MONO (4290 5310);
FORCEPROP 2 LASTPIN (4900 5600) $PN 6
J 0
(4910 5610);
DISPLAY 0.680851 (4910 5610);
PAINT MONO (4910 5610);
FORCEPROP 2 LASTPIN (4900 5550) $PN 9
J 0
(4910 5560);
DISPLAY 0.680851 (4910 5560);
PAINT MONO (4910 5560);
FORCEPROP 2 LASTPIN (4300 5600) $PN 10
J 2
(4290 5610);
DISPLAY 0.680851 (4290 5610);
PAINT MONO (4290 5610);
FORCEPROP 2 LAST VALUE PI3CSW12ZUAEX
J 2
(4750 5800);
DISPLAY 0.680851 (4750 5800);
FORCEPROP 2 LAST PART_TYPE SMLF
J 2
(4750 5850);
DISPLAY 0.680851 (4750 5850);
FORCEPROP 1 LAST MATERIAL IC
J 2
(4744 5669);
DISPLAY 0.723404 (4744 5669);
PAINT GREEN (4744 5669);
FORCEPROP 2 LAST SEC_TYPE 
J 0
(4750 5900);
DISPLAY 0.680851 (4750 5900);
DISPLAY INVISIBLE (4750 5900);
FORCEPROP 1 LAST CDS_LMAN_SYM_OUTLINE -150,200,150,-200
J 2
(4600 5450);
DISPLAY 0.468085 (4600 5450);
PAINT GREEN (4600 5450);
DISPLAY INVISIBLE (4600 5450);
FORCEPROP 1 LAST NEEDS_NO_SIZE TRUE
J 2
(4600 5450);
DISPLAY 0.723404 (4600 5450);
PAINT GREEN (4600 5450);
DISPLAY INVISIBLE (4600 5450);
FORCEPROP 2 LAST CDS_LIB pure_quanta
J 2
(4600 5450);
DISPLAY INVISIBLE (4600 5450);
FORCEPROP 1 LAST PATH I114
J 2
(4600 5450);
DISPLAY 0.723404 (4600 5450);
PAINT GREEN (4600 5450);
DISPLAY INVISIBLE (4600 5450);
FORCEPROP 1 LAST PART_NUMBER AL3CSW12000
J 2
(4750 5700);
DISPLAY 0.723404 (4750 5700);
PAINT GREEN (4750 5700);
DISPLAY INVISIBLE (4750 5700);
FORCEADD P1V0..1
(1150 2650);
FORCEPROP 3 LASTPIN (1150 2600) SIG_NAME P3V3_AUX\g
J 0
(1160 2610);
DISPLAY 0.659574 (1160 2610);
PAINT MONO (1160 2610);
DISPLAY INVISIBLE (1160 2610);
FORCEPROP 1 LAST HDL_POWER P3V3_AUX
J 1
(1150 2700);
DISPLAY 0.489362 (1150 2700);
PAINT GREEN (1150 2700);
FORCEPROP 2 LAST CDS_LIB pure_quanta_power
J 0
(1150 2650);
DISPLAY INVISIBLE (1150 2650);
FORCEPROP 1 LAST PATH I13
J 0
(1200 2675);
DISPLAY 0.872340 (1200 2675);
PAINT AQUA (1200 2675);
DISPLAY INVISIBLE (1200 2675);
FORCEADD Q_RES..1
(1650 2800);
FORCEPROP 1 LAST LOCATION R145
J 0
(1150 2825);
DISPLAY 0.489362 (1150 2825);
PAINT SKYBLUE (1150 2825);
FORCEPROP 0 LAST $SEC 1
J 0
(1550 2875);
DISPLAY 0.680851 (1550 2875);
PAINT MONO (1550 2875);
DISPLAY INVISIBLE (1550 2875);
FORCEPROP 0 LAST CDS_SEC 1
J 0
(1550 2875);
DISPLAY 1.021277 (1550 2875);
DISPLAY INVISIBLE (1550 2875);
FORCEPROP 1 LASTPIN (1550 2800) $PN 1
J 0
(1562 2812);
DISPLAY 0.489362 (1562 2812);
PAINT MONO (1562 2812);
FORCEPROP 1 LASTPIN (1750 2800) $PN 2
J 0
(1712 2812);
DISPLAY 0.489362 (1712 2812);
PAINT MONO (1712 2812);
FORCEPROP 1 LAST MATERIAL EMPTY
J 0
(1350 2825);
DISPLAY 0.489362 (1350 2825);
PAINT RED (1350 2825);
FORCEPROP 1 LAST VALUE 0
J 2
(1750 2825);
DISPLAY 0.489362 (1750 2825);
PAINT SKYBLUE (1750 2825);
FORCEPROP 2 LAST CDS_LIB pure_quanta
J 0
(1650 2800);
DISPLAY INVISIBLE (1650 2800);
FORCEPROP 1 LAST WATTAGE 1/16W
J 2
(1625 2650);
DISPLAY 0.510638 (1625 2650);
PAINT SKYBLUE (1625 2650);
DISPLAY INVISIBLE (1625 2650);
FORCEPROP 1 LAST TOLERANCE 5%
J 0
(1650 2700);
DISPLAY 0.510638 (1650 2700);
PAINT SKYBLUE (1650 2700);
DISPLAY INVISIBLE (1650 2700);
FORCEPROP 1 LAST PACK_TYPE 0402LF
J 0
(1650 2750);
DISPLAY 0.510638 (1650 2750);
PAINT SKYBLUE (1650 2750);
DISPLAY INVISIBLE (1650 2750);
FORCEPROP 1 LAST PATH I14
J 0
(1600 2950);
DISPLAY 0.978723 (1600 2950);
PAINT WHITE (1600 2950);
DISPLAY INVISIBLE (1600 2950);
FORCEPROP 1 LAST PART_NUMBER CS00002JB13
J 0
(1600 2900);
DISPLAY 0.510638 (1600 2900);
PAINT SKYBLUE (1600 2900);
DISPLAY INVISIBLE (1600 2900);
FORCEADD Q_RES..1
(1650 2875);
FORCEPROP 1 LAST LOCATION R144
J 0
(1150 2900);
DISPLAY 0.489362 (1150 2900);
PAINT SKYBLUE (1150 2900);
FORCEPROP 0 LAST $SEC 1
J 0
(1550 2950);
DISPLAY 0.680851 (1550 2950);
PAINT MONO (1550 2950);
DISPLAY INVISIBLE (1550 2950);
FORCEPROP 0 LAST CDS_SEC 1
J 0
(1550 2950);
DISPLAY 1.021277 (1550 2950);
DISPLAY INVISIBLE (1550 2950);
FORCEPROP 1 LASTPIN (1550 2875) $PN 1
J 0
(1562 2887);
DISPLAY 0.489362 (1562 2887);
PAINT MONO (1562 2887);
FORCEPROP 1 LASTPIN (1750 2875) $PN 2
J 0
(1712 2887);
DISPLAY 0.489362 (1712 2887);
PAINT MONO (1712 2887);
FORCEPROP 1 LAST MATERIAL EMPTY
J 0
(1350 2900);
DISPLAY 0.489362 (1350 2900);
PAINT RED (1350 2900);
FORCEPROP 1 LAST VALUE 0
J 2
(1750 2900);
DISPLAY 0.489362 (1750 2900);
PAINT SKYBLUE (1750 2900);
FORCEPROP 2 LAST CDS_LIB pure_quanta
J 0
(1650 2875);
DISPLAY INVISIBLE (1650 2875);
FORCEPROP 1 LAST WATTAGE 1/16W
J 2
(1625 2725);
DISPLAY 0.510638 (1625 2725);
PAINT SKYBLUE (1625 2725);
DISPLAY INVISIBLE (1625 2725);
FORCEPROP 1 LAST TOLERANCE 5%
J 0
(1650 2775);
DISPLAY 0.510638 (1650 2775);
PAINT SKYBLUE (1650 2775);
DISPLAY INVISIBLE (1650 2775);
FORCEPROP 1 LAST PACK_TYPE 0402LF
J 0
(1650 2825);
DISPLAY 0.510638 (1650 2825);
PAINT SKYBLUE (1650 2825);
DISPLAY INVISIBLE (1650 2825);
FORCEPROP 1 LAST PATH I15
J 0
(1600 3025);
DISPLAY 0.978723 (1600 3025);
PAINT WHITE (1600 3025);
DISPLAY INVISIBLE (1600 3025);
FORCEPROP 1 LAST PART_NUMBER CS00002JB13
J 0
(1600 2975);
DISPLAY 0.510638 (1600 2975);
PAINT SKYBLUE (1600 2975);
DISPLAY INVISIBLE (1600 2975);
FORCEADD Q_RES..1
(1700 3150);
FORCEPROP 1 LAST LOCATION R147
J 0
(1200 3175);
DISPLAY 0.489362 (1200 3175);
PAINT SKYBLUE (1200 3175);
FORCEPROP 0 LAST $SEC 1
J 0
(1600 3225);
DISPLAY 0.680851 (1600 3225);
PAINT MONO (1600 3225);
DISPLAY INVISIBLE (1600 3225);
FORCEPROP 0 LAST CDS_SEC 1
J 0
(1600 3225);
DISPLAY 1.021277 (1600 3225);
DISPLAY INVISIBLE (1600 3225);
FORCEPROP 1 LASTPIN (1600 3150) $PN 1
J 0
(1612 3162);
DISPLAY 0.489362 (1612 3162);
PAINT MONO (1612 3162);
FORCEPROP 1 LASTPIN (1800 3150) $PN 2
J 0
(1762 3162);
DISPLAY 0.489362 (1762 3162);
PAINT MONO (1762 3162);
FORCEPROP 1 LAST MATERIAL EMPTY
J 0
(1400 3175);
DISPLAY 0.489362 (1400 3175);
PAINT RED (1400 3175);
FORCEPROP 1 LAST VALUE 0
J 2
(1800 3175);
DISPLAY 0.489362 (1800 3175);
PAINT SKYBLUE (1800 3175);
FORCEPROP 2 LAST CDS_LIB pure_quanta
J 0
(1700 3150);
DISPLAY INVISIBLE (1700 3150);
FORCEPROP 1 LAST WATTAGE 1/16W
J 2
(1675 3000);
DISPLAY 0.510638 (1675 3000);
PAINT SKYBLUE (1675 3000);
DISPLAY INVISIBLE (1675 3000);
FORCEPROP 1 LAST TOLERANCE 5%
J 0
(1700 3050);
DISPLAY 0.510638 (1700 3050);
PAINT SKYBLUE (1700 3050);
DISPLAY INVISIBLE (1700 3050);
FORCEPROP 1 LAST PACK_TYPE 0402LF
J 0
(1700 3100);
DISPLAY 0.510638 (1700 3100);
PAINT SKYBLUE (1700 3100);
DISPLAY INVISIBLE (1700 3100);
FORCEPROP 1 LAST PATH I16
J 0
(1650 3300);
DISPLAY 0.978723 (1650 3300);
PAINT WHITE (1650 3300);
DISPLAY INVISIBLE (1650 3300);
FORCEPROP 1 LAST PART_NUMBER CS00002JB13
J 0
(1650 3250);
DISPLAY 0.510638 (1650 3250);
PAINT SKYBLUE (1650 3250);
DISPLAY INVISIBLE (1650 3250);
FORCEADD Q_RES..1
(1700 3225);
FORCEPROP 1 LAST LOCATION R146
J 0
(1200 3250);
DISPLAY 0.489362 (1200 3250);
PAINT SKYBLUE (1200 3250);
FORCEPROP 0 LAST $SEC 1
J 0
(1600 3300);
DISPLAY 0.680851 (1600 3300);
PAINT MONO (1600 3300);
DISPLAY INVISIBLE (1600 3300);
FORCEPROP 0 LAST CDS_SEC 1
J 0
(1600 3300);
DISPLAY 1.021277 (1600 3300);
DISPLAY INVISIBLE (1600 3300);
FORCEPROP 1 LASTPIN (1600 3225) $PN 1
J 0
(1612 3237);
DISPLAY 0.489362 (1612 3237);
PAINT MONO (1612 3237);
FORCEPROP 1 LASTPIN (1800 3225) $PN 2
J 0
(1762 3237);
DISPLAY 0.489362 (1762 3237);
PAINT MONO (1762 3237);
FORCEPROP 1 LAST VALUE 0
J 2
(1800 3250);
DISPLAY 0.489362 (1800 3250);
PAINT SKYBLUE (1800 3250);
FORCEPROP 1 LAST MATERIAL EMPTY
J 0
(1400 3250);
DISPLAY 0.489362 (1400 3250);
PAINT RED (1400 3250);
FORCEPROP 2 LAST CDS_LIB pure_quanta
J 0
(1700 3225);
DISPLAY INVISIBLE (1700 3225);
FORCEPROP 1 LAST WATTAGE 1/16W
J 2
(1675 3075);
DISPLAY 0.510638 (1675 3075);
PAINT SKYBLUE (1675 3075);
DISPLAY INVISIBLE (1675 3075);
FORCEPROP 1 LAST TOLERANCE 5%
J 0
(1700 3125);
DISPLAY 0.510638 (1700 3125);
PAINT SKYBLUE (1700 3125);
DISPLAY INVISIBLE (1700 3125);
FORCEPROP 1 LAST PACK_TYPE 0402LF
J 0
(1700 3175);
DISPLAY 0.510638 (1700 3175);
PAINT SKYBLUE (1700 3175);
DISPLAY INVISIBLE (1700 3175);
FORCEPROP 1 LAST PATH I17
J 0
(1650 3375);
DISPLAY 0.978723 (1650 3375);
PAINT WHITE (1650 3375);
DISPLAY INVISIBLE (1650 3375);
FORCEPROP 1 LAST PART_NUMBER CS00002JB13
J 0
(1650 3325);
DISPLAY 0.510638 (1650 3325);
PAINT SKYBLUE (1650 3325);
DISPLAY INVISIBLE (1650 3325);
FORCEADD UNIVERSAL_GND..1
(1225 1600);
FORCEPROP 3 LASTPIN (1225 1650) SIG_NAME GND\g
J 0
(1235 1660);
DISPLAY 0.659574 (1235 1660);
PAINT MONO (1235 1660);
DISPLAY INVISIBLE (1235 1660);
FORCEPROP 2 LAST CDS_LIB pure_quanta_power
J 0
(1225 1600);
DISPLAY INVISIBLE (1225 1600);
FORCEPROP 1 LAST HDL_POWER GND
J 1
(1250 1525);
DISPLAY 0.872340 (1250 1525);
PAINT GREEN (1250 1525);
DISPLAY INVISIBLE (1250 1525);
FORCEPROP 1 LAST PATH I18
J 0
(1300 1600);
DISPLAY 0.872340 (1300 1600);
PAINT AQUA (1300 1600);
DISPLAY INVISIBLE (1300 1600);
FORCEADD OFFPAGE..3
R 2
(-825 2025);
FORCEPROP 2 LAST $XR0 160 
J 0
(-1105 2025);
DISPLAY 0.638298 (-1105 2025);
PAINT MONO (-1105 2025);
FORCEPROP 2 LAST CDS_LIB standard
J 0
(-825 2025);
DISPLAY INVISIBLE (-825 2025);
FORCEPROP 1 LAST OFFPAGE TRUE
J 2
(-1150 1900);
DISPLAY 0.872340 (-1150 1900);
PAINT GREEN (-1150 1900);
DISPLAY INVISIBLE (-1150 1900);
FORCEPROP 1 LAST COMMENT_BODY TRUE
J 2
(-775 1925);
DISPLAY 0.872340 (-775 1925);
PAINT GREEN (-775 1925);
DISPLAY INVISIBLE (-775 1925);
FORCEPROP 2 LAST PATH I2
J 0
(-775 2100);
DISPLAY 0.680851 (-775 2100);
DISPLAY INVISIBLE (-775 2100);
FORCEADD UNIVERSAL_GND..1
(2125 3575);
FORCEPROP 3 LASTPIN (2125 3625) SIG_NAME GND\g
J 0
(2135 3635);
DISPLAY 0.659574 (2135 3635);
PAINT MONO (2135 3635);
DISPLAY INVISIBLE (2135 3635);
FORCEPROP 2 LAST CDS_LIB pure_quanta_power
J 0
(2125 3575);
DISPLAY INVISIBLE (2125 3575);
FORCEPROP 1 LAST HDL_POWER GND
J 1
(2150 3500);
DISPLAY 0.872340 (2150 3500);
PAINT GREEN (2150 3500);
DISPLAY INVISIBLE (2150 3500);
FORCEPROP 1 LAST PATH I21
J 0
(2200 3575);
DISPLAY 0.872340 (2200 3575);
PAINT AQUA (2200 3575);
DISPLAY INVISIBLE (2200 3575);
FORCEADD Q_RES..1
(3175 1775);
FORCEPROP 1 LAST LOCATION R1162
J 0
(2975 1775);
DISPLAY 0.489362 (2975 1775);
PAINT SKYBLUE (2975 1775);
FORCEPROP 0 LAST $SEC 1
J 0
(3050 1825);
DISPLAY 0.680851 (3050 1825);
PAINT MONO (3050 1825);
DISPLAY INVISIBLE (3050 1825);
FORCEPROP 0 LAST CDS_SEC 1
J 0
(3050 1825);
DISPLAY 1.021277 (3050 1825);
DISPLAY INVISIBLE (3050 1825);
FORCEPROP 1 LASTPIN (3075 1775) $PN 1
J 0
(3087 1787);
DISPLAY 0.489362 (3087 1787);
PAINT MONO (3087 1787);
FORCEPROP 1 LASTPIN (3275 1775) $PN 2
J 0
(3237 1787);
DISPLAY 0.489362 (3237 1787);
PAINT MONO (3237 1787);
FORCEPROP 1 LAST VALUE 0
J 2
(3375 1775);
DISPLAY 0.489362 (3375 1775);
PAINT SKYBLUE (3375 1775);
FORCEPROP 1 LAST PACK_TYPE 0402LF
J 0
(3225 1700);
DISPLAY 0.489362 (3225 1700);
PAINT SKYBLUE (3225 1700);
DISPLAY INVISIBLE (3225 1700);
FORCEPROP 1 LAST TOLERANCE 5%
J 0
(3150 1700);
DISPLAY 0.489362 (3150 1700);
PAINT SKYBLUE (3150 1700);
DISPLAY INVISIBLE (3150 1700);
FORCEPROP 1 LAST MATERIAL CHIP
J 0
(3600 1700);
DISPLAY 0.489362 (3600 1700);
PAINT SKYBLUE (3600 1700);
DISPLAY INVISIBLE (3600 1700);
FORCEPROP 1 LAST WATTAGE 1/16W
J 2
(3575 1700);
DISPLAY 0.489362 (3575 1700);
PAINT SKYBLUE (3575 1700);
DISPLAY INVISIBLE (3575 1700);
FORCEPROP 2 LAST CDS_LIB pure_quanta
J 0
(3175 1775);
DISPLAY INVISIBLE (3175 1775);
FORCEPROP 1 LAST PATH I22
J 0
(3125 1925);
DISPLAY 0.978723 (3125 1925);
PAINT WHITE (3125 1925);
DISPLAY INVISIBLE (3125 1925);
FORCEPROP 1 LAST PART_NUMBER CS00002JB13
J 0
(3200 1825);
DISPLAY 0.489362 (3200 1825);
PAINT SKYBLUE (3200 1825);
DISPLAY INVISIBLE (3200 1825);
FORCEADD Q_RES..1
(3175 1825);
FORCEPROP 1 LAST LOCATION R1161
J 0
(2975 1825);
DISPLAY 0.489362 (2975 1825);
PAINT SKYBLUE (2975 1825);
FORCEPROP 0 LAST $SEC 1
J 0
(3050 1875);
DISPLAY 0.680851 (3050 1875);
PAINT MONO (3050 1875);
DISPLAY INVISIBLE (3050 1875);
FORCEPROP 0 LAST CDS_SEC 1
J 0
(3050 1875);
DISPLAY 1.021277 (3050 1875);
DISPLAY INVISIBLE (3050 1875);
FORCEPROP 1 LASTPIN (3075 1825) $PN 1
J 0
(3087 1837);
DISPLAY 0.489362 (3087 1837);
PAINT MONO (3087 1837);
FORCEPROP 1 LASTPIN (3275 1825) $PN 2
J 0
(3237 1837);
DISPLAY 0.489362 (3237 1837);
PAINT MONO (3237 1837);
FORCEPROP 1 LAST VALUE 0
J 2
(3375 1825);
DISPLAY 0.489362 (3375 1825);
PAINT SKYBLUE (3375 1825);
FORCEPROP 2 LAST CDS_LIB pure_quanta
J 0
(3175 1825);
DISPLAY INVISIBLE (3175 1825);
FORCEPROP 1 LAST WATTAGE 1/16W
J 2
(3575 1750);
DISPLAY 0.489362 (3575 1750);
PAINT SKYBLUE (3575 1750);
DISPLAY INVISIBLE (3575 1750);
FORCEPROP 1 LAST MATERIAL CHIP
J 0
(3600 1750);
DISPLAY 0.489362 (3600 1750);
PAINT SKYBLUE (3600 1750);
DISPLAY INVISIBLE (3600 1750);
FORCEPROP 1 LAST TOLERANCE 5%
J 0
(3150 1750);
DISPLAY 0.489362 (3150 1750);
PAINT SKYBLUE (3150 1750);
DISPLAY INVISIBLE (3150 1750);
FORCEPROP 1 LAST PACK_TYPE 0402LF
J 0
(3225 1750);
DISPLAY 0.489362 (3225 1750);
PAINT SKYBLUE (3225 1750);
DISPLAY INVISIBLE (3225 1750);
FORCEPROP 1 LAST PATH I23
J 0
(3125 1975);
DISPLAY 0.978723 (3125 1975);
PAINT WHITE (3125 1975);
DISPLAY INVISIBLE (3125 1975);
FORCEPROP 1 LAST PART_NUMBER CS00002JB13
J 0
(3200 1875);
DISPLAY 0.489362 (3200 1875);
PAINT SKYBLUE (3200 1875);
DISPLAY INVISIBLE (3200 1875);
FORCEADD UNIVERSAL_GND..1
(2800 3350);
FORCEPROP 3 LASTPIN (2800 3400) SIG_NAME GND\g
J 0
(2810 3410);
DISPLAY 0.659574 (2810 3410);
PAINT MONO (2810 3410);
DISPLAY INVISIBLE (2810 3410);
FORCEPROP 2 LAST CDS_LIB pure_quanta_power
J 0
(2800 3350);
DISPLAY INVISIBLE (2800 3350);
FORCEPROP 1 LAST HDL_POWER GND
J 1
(2825 3275);
DISPLAY 0.872340 (2825 3275);
PAINT GREEN (2825 3275);
DISPLAY INVISIBLE (2825 3275);
FORCEPROP 1 LAST PATH I26
J 0
(2875 3350);
DISPLAY 0.872340 (2875 3350);
PAINT AQUA (2875 3350);
DISPLAY INVISIBLE (2875 3350);
FORCEADD Q_RES..2
(2800 3600);
FORCEPROP 1 LAST LOCATION R5004
J 0
(2845 3725);
DISPLAY 0.489362 (2845 3725);
PAINT SKYBLUE (2845 3725);
FORCEPROP 0 LAST $SEC 1
J 0
(2850 3750);
DISPLAY 0.680851 (2850 3750);
PAINT MONO (2850 3750);
DISPLAY INVISIBLE (2850 3750);
FORCEPROP 0 LAST CDS_SEC 1
J 0
(2850 3750);
DISPLAY 0.680851 (2850 3750);
DISPLAY INVISIBLE (2850 3750);
FORCEPROP 1 LASTPIN (2800 3700) $PN 1
J 0
(2805 3662);
DISPLAY 0.787234 (2805 3662);
PAINT MONO (2805 3662);
FORCEPROP 1 LASTPIN (2800 3500) $PN 2
J 0
(2805 3510);
DISPLAY 0.787234 (2805 3510);
PAINT MONO (2805 3510);
FORCEPROP 1 LAST MATERIAL CHIP
J 0
(2840 3525);
DISPLAY 0.489362 (2840 3525);
PAINT SKYBLUE (2840 3525);
FORCEPROP 1 LAST PACK_TYPE 0402LF
J 0
(2850 3475);
DISPLAY 0.489362 (2850 3475);
PAINT SKYBLUE (2850 3475);
FORCEPROP 1 LAST TOLERANCE 1%
J 0
(2845 3625);
DISPLAY 0.489362 (2845 3625);
PAINT SKYBLUE (2845 3625);
FORCEPROP 1 LAST VALUE 10K
J 0
(2845 3675);
DISPLAY 0.489362 (2845 3675);
PAINT SKYBLUE (2845 3675);
FORCEPROP 1 LAST WATTAGE 1/16W
J 0
(2840 3575);
DISPLAY 0.489362 (2840 3575);
PAINT SKYBLUE (2840 3575);
FORCEPROP 2 LAST CDS_LIB pure_quanta
J 0
(2800 3600);
DISPLAY INVISIBLE (2800 3600);
FORCEPROP 1 LAST PATH I27
J 0
(2850 3775);
DISPLAY 0.978723 (2850 3775);
PAINT WHITE (2850 3775);
DISPLAY INVISIBLE (2850 3775);
FORCEPROP 1 LAST PART_NUMBER CS31002FB08
J 0
(2840 3475);
DISPLAY 0.489362 (2840 3475);
PAINT SKYBLUE (2840 3475);
DISPLAY INVISIBLE (2840 3475);
FORCEADD UNIVERSAL_GND..1
(175 4150);
FORCEPROP 3 LASTPIN (175 4200) SIG_NAME GND\g
J 0
(185 4210);
DISPLAY 0.659574 (185 4210);
PAINT MONO (185 4210);
DISPLAY INVISIBLE (185 4210);
FORCEPROP 2 LAST CDS_LIB pure_quanta_power
J 0
(175 4150);
DISPLAY INVISIBLE (175 4150);
FORCEPROP 1 LAST HDL_POWER GND
J 1
(200 4075);
DISPLAY 0.872340 (200 4075);
PAINT GREEN (200 4075);
DISPLAY INVISIBLE (200 4075);
FORCEPROP 1 LAST PATH I28
J 0
(250 4150);
DISPLAY 0.872340 (250 4150);
PAINT AQUA (250 4150);
DISPLAY INVISIBLE (250 4150);
FORCEADD Q_RES..1
(425 4525);
FORCEPROP 1 LAST LOCATION R139
J 0
(350 4550);
DISPLAY 0.489362 (350 4550);
PAINT SKYBLUE (350 4550);
FORCEPROP 0 LAST $SEC 1
J 0
(525 4575);
DISPLAY 0.680851 (525 4575);
PAINT MONO (525 4575);
DISPLAY INVISIBLE (525 4575);
FORCEPROP 0 LAST CDS_SEC 1
J 0
(525 4575);
DISPLAY 1.021277 (525 4575);
DISPLAY INVISIBLE (525 4575);
FORCEPROP 1 LASTPIN (325 4525) $PN 1
J 0
(337 4537);
DISPLAY 0.489362 (337 4537);
PAINT MONO (337 4537);
FORCEPROP 1 LASTPIN (525 4525) $PN 2
J 0
(487 4537);
DISPLAY 0.489362 (487 4537);
PAINT MONO (487 4537);
FORCEPROP 1 LAST VALUE 0
J 2
(525 4550);
DISPLAY 0.489362 (525 4550);
PAINT SKYBLUE (525 4550);
FORCEPROP 1 LAST MATERIAL EMPTY
J 0
(375 4475);
DISPLAY 0.489362 (375 4475);
PAINT RED (375 4475);
FORCEPROP 2 LAST CDS_LIB pure_quanta
J 0
(425 4525);
DISPLAY INVISIBLE (425 4525);
FORCEPROP 1 LAST WATTAGE 1/16W
J 2
(400 4375);
DISPLAY 0.510638 (400 4375);
PAINT SKYBLUE (400 4375);
DISPLAY INVISIBLE (400 4375);
FORCEPROP 1 LAST TOLERANCE 5%
J 0
(425 4425);
DISPLAY 0.510638 (425 4425);
PAINT SKYBLUE (425 4425);
DISPLAY INVISIBLE (425 4425);
FORCEPROP 1 LAST PACK_TYPE 0402LF
J 0
(425 4475);
DISPLAY 0.510638 (425 4475);
PAINT SKYBLUE (425 4475);
DISPLAY INVISIBLE (425 4475);
FORCEPROP 1 LAST PATH I30
J 0
(375 4675);
DISPLAY 0.978723 (375 4675);
PAINT WHITE (375 4675);
DISPLAY INVISIBLE (375 4675);
FORCEPROP 1 LAST PART_NUMBER CS00002JB13
J 0
(375 4625);
DISPLAY 0.510638 (375 4625);
PAINT SKYBLUE (375 4625);
DISPLAY INVISIBLE (375 4625);
FORCEADD UNIVERSAL_GND..1
(700 4150);
FORCEPROP 3 LASTPIN (700 4200) SIG_NAME GND\g
J 0
(710 4210);
DISPLAY 0.659574 (710 4210);
PAINT MONO (710 4210);
DISPLAY INVISIBLE (710 4210);
FORCEPROP 2 LAST CDS_LIB pure_quanta_power
J 0
(700 4150);
DISPLAY INVISIBLE (700 4150);
FORCEPROP 1 LAST HDL_POWER GND
J 1
(725 4075);
DISPLAY 0.872340 (725 4075);
PAINT GREEN (725 4075);
DISPLAY INVISIBLE (725 4075);
FORCEPROP 1 LAST PATH I31
J 0
(775 4150);
DISPLAY 0.872340 (775 4150);
PAINT AQUA (775 4150);
DISPLAY INVISIBLE (775 4150);
FORCEADD P1V0..1
(875 4700);
FORCEPROP 3 LASTPIN (875 4650) SIG_NAME PVDD18_S5_P0\g
J 0
(885 4660);
DISPLAY 0.659574 (885 4660);
PAINT MONO (885 4660);
DISPLAY INVISIBLE (885 4660);
FORCEPROP 1 LAST HDL_POWER PVDD18_S5_P0
J 1
(875 4750);
DISPLAY 0.489362 (875 4750);
PAINT GREEN (875 4750);
FORCEPROP 2 LAST CDS_LIB pure_quanta_power
J 0
(875 4700);
DISPLAY INVISIBLE (875 4700);
FORCEPROP 1 LAST PATH I33
J 0
(925 4725);
DISPLAY 0.872340 (925 4725);
PAINT AQUA (925 4725);
DISPLAY INVISIBLE (925 4725);
FORCEADD Q_RES..1
(1650 4925);
FORCEPROP 1 LAST LOCATION R143
J 0
(1150 4950);
DISPLAY 0.489362 (1150 4950);
PAINT SKYBLUE (1150 4950);
FORCEPROP 0 LAST $SEC 1
J 0
(1550 5000);
DISPLAY 0.680851 (1550 5000);
PAINT MONO (1550 5000);
DISPLAY INVISIBLE (1550 5000);
FORCEPROP 0 LAST CDS_SEC 1
J 0
(1550 5000);
DISPLAY 1.021277 (1550 5000);
DISPLAY INVISIBLE (1550 5000);
FORCEPROP 1 LASTPIN (1550 4925) $PN 1
J 0
(1562 4937);
DISPLAY 0.489362 (1562 4937);
PAINT MONO (1562 4937);
FORCEPROP 1 LASTPIN (1750 4925) $PN 2
J 0
(1712 4937);
DISPLAY 0.489362 (1712 4937);
PAINT MONO (1712 4937);
FORCEPROP 1 LAST MATERIAL EMPTY
J 0
(1350 4950);
DISPLAY 0.489362 (1350 4950);
PAINT RED (1350 4950);
FORCEPROP 1 LAST VALUE 0
J 2
(1750 4950);
DISPLAY 0.489362 (1750 4950);
PAINT SKYBLUE (1750 4950);
FORCEPROP 2 LAST CDS_LIB pure_quanta
J 0
(1650 4925);
DISPLAY INVISIBLE (1650 4925);
FORCEPROP 1 LAST WATTAGE 1/16W
J 2
(1625 4775);
DISPLAY 0.510638 (1625 4775);
PAINT SKYBLUE (1625 4775);
DISPLAY INVISIBLE (1625 4775);
FORCEPROP 1 LAST TOLERANCE 5%
J 0
(1650 4825);
DISPLAY 0.510638 (1650 4825);
PAINT SKYBLUE (1650 4825);
DISPLAY INVISIBLE (1650 4825);
FORCEPROP 1 LAST PACK_TYPE 0402LF
J 0
(1650 4875);
DISPLAY 0.510638 (1650 4875);
PAINT SKYBLUE (1650 4875);
DISPLAY INVISIBLE (1650 4875);
FORCEPROP 1 LAST PATH I34
J 0
(1600 5075);
DISPLAY 0.978723 (1600 5075);
PAINT WHITE (1600 5075);
DISPLAY INVISIBLE (1600 5075);
FORCEPROP 1 LAST PART_NUMBER CS00002JB13
J 0
(1600 5025);
DISPLAY 0.510638 (1600 5025);
PAINT SKYBLUE (1600 5025);
DISPLAY INVISIBLE (1600 5025);
FORCEADD Q_RES..1
(1650 5000);
FORCEPROP 1 LAST LOCATION R142
J 0
(1150 5025);
DISPLAY 0.489362 (1150 5025);
PAINT SKYBLUE (1150 5025);
FORCEPROP 0 LAST $SEC 1
J 0
(1550 5075);
DISPLAY 0.680851 (1550 5075);
PAINT MONO (1550 5075);
DISPLAY INVISIBLE (1550 5075);
FORCEPROP 0 LAST CDS_SEC 1
J 0
(1550 5075);
DISPLAY 1.021277 (1550 5075);
DISPLAY INVISIBLE (1550 5075);
FORCEPROP 1 LASTPIN (1550 5000) $PN 1
J 0
(1562 5012);
DISPLAY 0.489362 (1562 5012);
PAINT MONO (1562 5012);
FORCEPROP 1 LASTPIN (1750 5000) $PN 2
J 0
(1712 5012);
DISPLAY 0.489362 (1712 5012);
PAINT MONO (1712 5012);
FORCEPROP 1 LAST MATERIAL EMPTY
J 0
(1350 5025);
DISPLAY 0.489362 (1350 5025);
PAINT RED (1350 5025);
FORCEPROP 1 LAST VALUE 0
J 2
(1750 5025);
DISPLAY 0.489362 (1750 5025);
PAINT SKYBLUE (1750 5025);
FORCEPROP 2 LAST CDS_LIB pure_quanta
J 0
(1650 5000);
DISPLAY INVISIBLE (1650 5000);
FORCEPROP 1 LAST WATTAGE 1/16W
J 2
(1625 4850);
DISPLAY 0.510638 (1625 4850);
PAINT SKYBLUE (1625 4850);
DISPLAY INVISIBLE (1625 4850);
FORCEPROP 1 LAST TOLERANCE 5%
J 0
(1650 4900);
DISPLAY 0.510638 (1650 4900);
PAINT SKYBLUE (1650 4900);
DISPLAY INVISIBLE (1650 4900);
FORCEPROP 1 LAST PACK_TYPE 0402LF
J 0
(1650 4950);
DISPLAY 0.510638 (1650 4950);
PAINT SKYBLUE (1650 4950);
DISPLAY INVISIBLE (1650 4950);
FORCEPROP 1 LAST PATH I35
J 0
(1600 5150);
DISPLAY 0.978723 (1600 5150);
PAINT WHITE (1600 5150);
DISPLAY INVISIBLE (1600 5150);
FORCEPROP 1 LAST PART_NUMBER CS00002JB13
J 0
(1600 5100);
DISPLAY 0.510638 (1600 5100);
PAINT SKYBLUE (1600 5100);
DISPLAY INVISIBLE (1600 5100);
FORCEADD Q_RES..1
(3150 3975);
FORCEPROP 1 LAST LOCATION R1156
J 0
(2950 3975);
DISPLAY 0.489362 (2950 3975);
PAINT SKYBLUE (2950 3975);
FORCEPROP 0 LAST $SEC 1
J 0
(3025 4025);
DISPLAY 0.680851 (3025 4025);
PAINT MONO (3025 4025);
DISPLAY INVISIBLE (3025 4025);
FORCEPROP 0 LAST CDS_SEC 1
J 0
(3025 4025);
DISPLAY 1.021277 (3025 4025);
DISPLAY INVISIBLE (3025 4025);
FORCEPROP 1 LASTPIN (3050 3975) $PN 1
J 0
(3062 3987);
DISPLAY 0.489362 (3062 3987);
PAINT MONO (3062 3987);
FORCEPROP 1 LASTPIN (3250 3975) $PN 2
J 0
(3212 3987);
DISPLAY 0.489362 (3212 3987);
PAINT MONO (3212 3987);
FORCEPROP 1 LAST MATERIAL EMPTY
J 0
(2825 3975);
DISPLAY 0.489362 (2825 3975);
PAINT RED (2825 3975);
FORCEPROP 1 LAST VALUE 33
J 2
(3350 3975);
DISPLAY 0.617021 (3350 3975);
PAINT SKYBLUE (3350 3975);
FORCEPROP 2 LAST CDS_LIB pure_quanta
J 0
(3150 3975);
DISPLAY INVISIBLE (3150 3975);
FORCEPROP 1 LAST WATTAGE 1/16W
J 2
(3550 3900);
DISPLAY 0.489362 (3550 3900);
PAINT SKYBLUE (3550 3900);
DISPLAY INVISIBLE (3550 3900);
FORCEPROP 1 LAST TOLERANCE 5%
J 0
(3125 3900);
DISPLAY 0.489362 (3125 3900);
PAINT SKYBLUE (3125 3900);
DISPLAY INVISIBLE (3125 3900);
FORCEPROP 1 LAST PACK_TYPE 0402LF
J 0
(3200 3900);
DISPLAY 0.489362 (3200 3900);
PAINT SKYBLUE (3200 3900);
DISPLAY INVISIBLE (3200 3900);
FORCEPROP 1 LAST PATH I38
J 0
(3100 4125);
DISPLAY 0.978723 (3100 4125);
PAINT WHITE (3100 4125);
DISPLAY INVISIBLE (3100 4125);
FORCEPROP 1 LAST PART_NUMBER CS03302JB10
J 0
(3175 4025);
DISPLAY 0.489362 (3175 4025);
PAINT SKYBLUE (3175 4025);
DISPLAY INVISIBLE (3175 4025);
FORCEADD Q_RES..1
(3150 4025);
FORCEPROP 1 LAST LOCATION R1155
J 0
(2950 4025);
DISPLAY 0.489362 (2950 4025);
PAINT SKYBLUE (2950 4025);
FORCEPROP 0 LAST $SEC 1
J 0
(3025 4075);
DISPLAY 0.680851 (3025 4075);
PAINT MONO (3025 4075);
DISPLAY INVISIBLE (3025 4075);
FORCEPROP 0 LAST CDS_SEC 1
J 0
(3025 4075);
DISPLAY 1.021277 (3025 4075);
DISPLAY INVISIBLE (3025 4075);
FORCEPROP 1 LASTPIN (3050 4025) $PN 1
J 0
(3062 4037);
DISPLAY 0.489362 (3062 4037);
PAINT MONO (3062 4037);
FORCEPROP 1 LASTPIN (3250 4025) $PN 2
J 0
(3212 4037);
DISPLAY 0.489362 (3212 4037);
PAINT MONO (3212 4037);
FORCEPROP 1 LAST MATERIAL EMPTY
J 0
(2825 4025);
DISPLAY 0.489362 (2825 4025);
PAINT RED (2825 4025);
FORCEPROP 1 LAST VALUE 33
J 2
(3350 4025);
DISPLAY 0.617021 (3350 4025);
PAINT SKYBLUE (3350 4025);
FORCEPROP 1 LAST PACK_TYPE 0402LF
J 0
(3200 3950);
DISPLAY 0.489362 (3200 3950);
PAINT SKYBLUE (3200 3950);
DISPLAY INVISIBLE (3200 3950);
FORCEPROP 1 LAST TOLERANCE 5%
J 0
(3125 3950);
DISPLAY 0.489362 (3125 3950);
PAINT SKYBLUE (3125 3950);
DISPLAY INVISIBLE (3125 3950);
FORCEPROP 1 LAST WATTAGE 1/16W
J 2
(3550 3950);
DISPLAY 0.489362 (3550 3950);
PAINT SKYBLUE (3550 3950);
DISPLAY INVISIBLE (3550 3950);
FORCEPROP 2 LAST CDS_LIB pure_quanta
J 0
(3150 4025);
DISPLAY INVISIBLE (3150 4025);
FORCEPROP 1 LAST PATH I39
J 0
(3100 4175);
DISPLAY 0.978723 (3100 4175);
PAINT WHITE (3100 4175);
DISPLAY INVISIBLE (3100 4175);
FORCEPROP 1 LAST PART_NUMBER CS03302JB10
J 0
(3175 4075);
DISPLAY 0.489362 (3175 4075);
PAINT SKYBLUE (3175 4075);
DISPLAY INVISIBLE (3175 4075);
FORCEADD OFFPAGE..3
(4050 1825);
FORCEPROP 2 LAST $XR1 55 
J 0
(4384 1825);
DISPLAY 0.638298 (4384 1825);
PAINT MONO (4384 1825);
FORCEPROP 2 LAST $XR0 161 
J 0
(4264 1825);
DISPLAY 0.638298 (4264 1825);
PAINT MONO (4264 1825);
FORCEPROP 2 LAST CDS_LIB standard
J 0
(4050 1825);
DISPLAY INVISIBLE (4050 1825);
FORCEPROP 1 LAST OFFPAGE TRUE
J 0
(4375 1700);
DISPLAY 0.872340 (4375 1700);
PAINT GREEN (4375 1700);
DISPLAY INVISIBLE (4375 1700);
FORCEPROP 1 LAST COMMENT_BODY TRUE
J 0
(4000 1725);
DISPLAY 0.872340 (4000 1725);
PAINT PEACH (4000 1725);
DISPLAY INVISIBLE (4000 1725);
FORCEPROP 2 LAST PATH I40
J 0
(4400 1875);
DISPLAY 0.680851 (4400 1875);
DISPLAY INVISIBLE (4400 1875);
FORCEADD OFFPAGE..3
(4050 1925);
FORCEPROP 2 LAST $XR1 161 
J 0
(4354 1925);
DISPLAY 0.638298 (4354 1925);
PAINT MONO (4354 1925);
FORCEPROP 2 LAST $XR0 28 
J 0
(4264 1925);
DISPLAY 0.638298 (4264 1925);
PAINT MONO (4264 1925);
FORCEPROP 2 LAST CDS_LIB standard
J 0
(4050 1925);
DISPLAY INVISIBLE (4050 1925);
FORCEPROP 1 LAST OFFPAGE TRUE
J 0
(4375 1800);
DISPLAY 0.872340 (4375 1800);
PAINT GREEN (4375 1800);
DISPLAY INVISIBLE (4375 1800);
FORCEPROP 1 LAST COMMENT_BODY TRUE
J 0
(4000 1825);
DISPLAY 0.872340 (4000 1825);
PAINT PEACH (4000 1825);
DISPLAY INVISIBLE (4000 1825);
FORCEPROP 2 LAST PATH I42
J 0
(4400 1975);
DISPLAY 0.680851 (4400 1975);
DISPLAY INVISIBLE (4400 1975);
FORCEADD OFFPAGE..5
(5000 2375);
FORCEPROP 2 LAST $XR1 55 
J 0
(4655 2375);
DISPLAY 0.638298 (4655 2375);
PAINT MONO (4655 2375);
FORCEPROP 2 LAST $XR0 161 
J 0
(4745 2375);
DISPLAY 0.638298 (4745 2375);
PAINT MONO (4745 2375);
FORCEPROP 2 LAST CDS_LIB standard
J 0
(5000 2375);
DISPLAY INVISIBLE (5000 2375);
FORCEPROP 1 LAST OFFPAGE TRUE
J 0
(5325 2250);
DISPLAY 0.872340 (5325 2250);
PAINT GREEN (5325 2250);
DISPLAY INVISIBLE (5325 2250);
FORCEPROP 1 LAST COMMENT_BODY TRUE
J 0
(5100 2300);
DISPLAY 0.872340 (5100 2300);
PAINT GREEN (5100 2300);
DISPLAY INVISIBLE (5100 2300);
FORCEPROP 2 LAST PATH I44
J 0
(4725 2425);
DISPLAY 0.680851 (4725 2425);
DISPLAY INVISIBLE (4725 2425);
FORCEADD OFFPAGE..5
(5000 2325);
FORCEPROP 2 LAST $XR1 161 
J 0
(4656 2325);
DISPLAY 0.638298 (4656 2325);
PAINT MONO (4656 2325);
FORCEPROP 2 LAST $XR0 55 
J 0
(4776 2325);
DISPLAY 0.638298 (4776 2325);
PAINT MONO (4776 2325);
FORCEPROP 2 LAST CDS_LIB standard
J 0
(5000 2325);
DISPLAY INVISIBLE (5000 2325);
FORCEPROP 1 LAST OFFPAGE TRUE
J 0
(5325 2200);
DISPLAY 0.872340 (5325 2200);
PAINT GREEN (5325 2200);
DISPLAY INVISIBLE (5325 2200);
FORCEPROP 1 LAST COMMENT_BODY TRUE
J 0
(5100 2250);
DISPLAY 0.872340 (5100 2250);
PAINT GREEN (5100 2250);
DISPLAY INVISIBLE (5100 2250);
FORCEPROP 2 LAST PATH I45
J 0
(4750 2375);
DISPLAY 0.680851 (4750 2375);
DISPLAY INVISIBLE (4750 2375);
FORCEADD OFFPAGE..5
(5000 2425);
FORCEPROP 2 LAST $XR1 54 
J 0
(4655 2425);
DISPLAY 0.638298 (4655 2425);
PAINT MONO (4655 2425);
FORCEPROP 2 LAST $XR0 161 
J 0
(4745 2425);
DISPLAY 0.638298 (4745 2425);
PAINT MONO (4745 2425);
FORCEPROP 2 LAST CDS_LIB standard
J 0
(5000 2425);
DISPLAY INVISIBLE (5000 2425);
FORCEPROP 1 LAST OFFPAGE TRUE
J 0
(5325 2300);
DISPLAY 0.872340 (5325 2300);
PAINT GREEN (5325 2300);
DISPLAY INVISIBLE (5325 2300);
FORCEPROP 1 LAST COMMENT_BODY TRUE
J 0
(5100 2350);
DISPLAY 0.872340 (5100 2350);
PAINT GREEN (5100 2350);
DISPLAY INVISIBLE (5100 2350);
FORCEPROP 2 LAST PATH I46
J 0
(4725 2475);
DISPLAY 0.680851 (4725 2475);
DISPLAY INVISIBLE (4725 2475);
FORCEADD OFFPAGE..5
(5000 2475);
FORCEPROP 2 LAST $XR1 54 
J 0
(4655 2475);
DISPLAY 0.638298 (4655 2475);
PAINT MONO (4655 2475);
FORCEPROP 2 LAST $XR0 161 
J 0
(4745 2475);
DISPLAY 0.638298 (4745 2475);
PAINT MONO (4745 2475);
FORCEPROP 2 LAST CDS_LIB standard
J 0
(5000 2475);
DISPLAY INVISIBLE (5000 2475);
FORCEPROP 1 LAST OFFPAGE TRUE
J 0
(5325 2350);
DISPLAY 0.872340 (5325 2350);
PAINT GREEN (5325 2350);
DISPLAY INVISIBLE (5325 2350);
FORCEPROP 1 LAST COMMENT_BODY TRUE
J 0
(5100 2400);
DISPLAY 0.872340 (5100 2400);
PAINT GREEN (5100 2400);
DISPLAY INVISIBLE (5100 2400);
FORCEPROP 2 LAST PATH I47
J 0
(4725 2525);
DISPLAY 0.680851 (4725 2525);
DISPLAY INVISIBLE (4725 2525);
FORCEADD OFFPAGE..5
(5125 3275);
FORCEPROP 2 LAST $XR1 161 
J 0
(4751 3275);
DISPLAY 0.638298 (4751 3275);
PAINT MONO (4751 3275);
FORCEPROP 2 LAST $XR0 28 
J 0
(4871 3275);
DISPLAY 0.638298 (4871 3275);
PAINT MONO (4871 3275);
FORCEPROP 2 LAST CDS_LIB standard
J 0
(5125 3275);
DISPLAY INVISIBLE (5125 3275);
FORCEPROP 1 LAST OFFPAGE TRUE
J 0
(5450 3150);
DISPLAY 0.872340 (5450 3150);
PAINT GREEN (5450 3150);
DISPLAY INVISIBLE (5450 3150);
FORCEPROP 1 LAST COMMENT_BODY TRUE
J 0
(5225 3200);
DISPLAY 0.872340 (5225 3200);
PAINT GREEN (5225 3200);
DISPLAY INVISIBLE (5225 3200);
FORCEPROP 2 LAST PATH I48
J 0
(4875 3325);
DISPLAY 0.680851 (4875 3325);
DISPLAY INVISIBLE (4875 3325);
FORCEADD OFFPAGE..5
(5125 3325);
FORCEPROP 2 LAST $XR1 161 
J 0
(4751 3325);
DISPLAY 0.638298 (4751 3325);
PAINT MONO (4751 3325);
FORCEPROP 2 LAST $XR0 28 
J 0
(4871 3325);
DISPLAY 0.638298 (4871 3325);
PAINT MONO (4871 3325);
FORCEPROP 2 LAST CDS_LIB standard
J 0
(5125 3325);
DISPLAY INVISIBLE (5125 3325);
FORCEPROP 1 LAST OFFPAGE TRUE
J 0
(5450 3200);
DISPLAY 0.872340 (5450 3200);
PAINT GREEN (5450 3200);
DISPLAY INVISIBLE (5450 3200);
FORCEPROP 1 LAST COMMENT_BODY TRUE
J 0
(5225 3250);
DISPLAY 0.872340 (5225 3250);
PAINT GREEN (5225 3250);
DISPLAY INVISIBLE (5225 3250);
FORCEPROP 2 LAST PATH I49
J 0
(4875 3375);
DISPLAY 0.680851 (4875 3375);
DISPLAY INVISIBLE (4875 3375);
FORCEADD Q_RES..1
(1725 1025);
FORCEPROP 1 LAST LOCATION R358
J 0
(1225 1025);
DISPLAY 0.489362 (1225 1025);
PAINT SKYBLUE (1225 1025);
FORCEPROP 0 LAST $SEC 1
J 0
(1825 1075);
DISPLAY 0.680851 (1825 1075);
PAINT MONO (1825 1075);
DISPLAY INVISIBLE (1825 1075);
FORCEPROP 0 LAST CDS_SEC 1
J 0
(1825 1075);
DISPLAY 1.021277 (1825 1075);
DISPLAY INVISIBLE (1825 1075);
FORCEPROP 1 LASTPIN (1625 1025) $PN 1
J 0
(1637 1037);
DISPLAY 0.489362 (1637 1037);
PAINT MONO (1637 1037);
FORCEPROP 1 LASTPIN (1825 1025) $PN 2
J 0
(1787 1037);
DISPLAY 0.489362 (1787 1037);
PAINT MONO (1787 1037);
FORCEPROP 1 LAST VALUE 0
J 2
(1825 1050);
DISPLAY 0.489362 (1825 1050);
PAINT SKYBLUE (1825 1050);
FORCEPROP 1 LAST MATERIAL EMPTY
J 0
(1425 1050);
DISPLAY 0.489362 (1425 1050);
PAINT RED (1425 1050);
FORCEPROP 2 LAST CDS_LIB pure_quanta
J 0
(1725 1025);
DISPLAY INVISIBLE (1725 1025);
FORCEPROP 1 LAST WATTAGE 1/16W
J 2
(1700 875);
DISPLAY 0.510638 (1700 875);
PAINT SKYBLUE (1700 875);
DISPLAY INVISIBLE (1700 875);
FORCEPROP 1 LAST TOLERANCE 5%
J 0
(1725 925);
DISPLAY 0.510638 (1725 925);
PAINT SKYBLUE (1725 925);
DISPLAY INVISIBLE (1725 925);
FORCEPROP 1 LAST PACK_TYPE 0402LF
J 0
(1725 975);
DISPLAY 0.510638 (1725 975);
PAINT SKYBLUE (1725 975);
DISPLAY INVISIBLE (1725 975);
FORCEPROP 1 LAST PATH I5
J 0
(1675 1175);
DISPLAY 0.978723 (1675 1175);
PAINT WHITE (1675 1175);
DISPLAY INVISIBLE (1675 1175);
FORCEPROP 1 LAST PART_NUMBER CS00002JB13
J 0
(1675 1125);
DISPLAY 0.510638 (1675 1125);
PAINT SKYBLUE (1675 1125);
DISPLAY INVISIBLE (1675 1125);
FORCEADD OFFPAGE..5
(5125 3425);
FORCEPROP 2 LAST $XR1 27 
J 0
(4750 3425);
DISPLAY 0.638298 (4750 3425);
PAINT MONO (4750 3425);
FORCEPROP 2 LAST $XR0 161 
J 0
(4840 3425);
DISPLAY 0.638298 (4840 3425);
PAINT MONO (4840 3425);
FORCEPROP 2 LAST CDS_LIB standard
J 0
(5125 3425);
DISPLAY INVISIBLE (5125 3425);
FORCEPROP 1 LAST OFFPAGE TRUE
J 0
(5450 3300);
DISPLAY 0.872340 (5450 3300);
PAINT GREEN (5450 3300);
DISPLAY INVISIBLE (5450 3300);
FORCEPROP 1 LAST COMMENT_BODY TRUE
J 0
(5225 3350);
DISPLAY 0.872340 (5225 3350);
PAINT GREEN (5225 3350);
DISPLAY INVISIBLE (5225 3350);
FORCEPROP 2 LAST PATH I50
J 0
(4875 3475);
DISPLAY 0.680851 (4875 3475);
DISPLAY INVISIBLE (4875 3475);
FORCEADD OFFPAGE..5
(5125 3375);
FORCEPROP 2 LAST $XR1 27 
J 0
(4750 3375);
DISPLAY 0.638298 (4750 3375);
PAINT MONO (4750 3375);
FORCEPROP 2 LAST $XR0 161 
J 0
(4840 3375);
DISPLAY 0.638298 (4840 3375);
PAINT MONO (4840 3375);
FORCEPROP 2 LAST CDS_LIB standard
J 0
(5125 3375);
DISPLAY INVISIBLE (5125 3375);
FORCEPROP 1 LAST OFFPAGE TRUE
J 0
(5450 3250);
DISPLAY 0.872340 (5450 3250);
PAINT GREEN (5450 3250);
DISPLAY INVISIBLE (5450 3250);
FORCEPROP 1 LAST COMMENT_BODY TRUE
J 0
(5225 3300);
DISPLAY 0.872340 (5225 3300);
PAINT GREEN (5225 3300);
DISPLAY INVISIBLE (5225 3300);
FORCEPROP 2 LAST PATH I51
J 0
(4875 3425);
DISPLAY 0.680851 (4875 3425);
DISPLAY INVISIBLE (4875 3425);
FORCEADD Q_RES..2
(5900 2725);
FORCEPROP 1 LAST LOCATION R359
J 0
(5945 2850);
DISPLAY 0.489362 (5945 2850);
PAINT SKYBLUE (5945 2850);
FORCEPROP 0 LAST $SEC 1
J 0
(5950 2900);
DISPLAY 0.680851 (5950 2900);
PAINT MONO (5950 2900);
DISPLAY INVISIBLE (5950 2900);
FORCEPROP 0 LAST CDS_SEC 1
J 0
(5950 2900);
DISPLAY 1.021277 (5950 2900);
DISPLAY INVISIBLE (5950 2900);
FORCEPROP 1 LASTPIN (5900 2825) $PN 1
J 0
(5905 2787);
DISPLAY 0.489362 (5905 2787);
PAINT MONO (5905 2787);
FORCEPROP 1 LASTPIN (5900 2625) $PN 2
J 0
(5905 2635);
DISPLAY 0.489362 (5905 2635);
PAINT MONO (5905 2635);
FORCEPROP 1 LAST VALUE 1K
J 0
(5945 2800);
DISPLAY 0.489362 (5945 2800);
PAINT SKYBLUE (5945 2800);
FORCEPROP 1 LAST TOLERANCE 1%
J 0
(5945 2750);
DISPLAY 0.489362 (5945 2750);
PAINT SKYBLUE (5945 2750);
FORCEPROP 1 LAST WATTAGE 1/16W
J 0
(5940 2700);
DISPLAY 0.489362 (5940 2700);
PAINT SKYBLUE (5940 2700);
FORCEPROP 1 LAST MATERIAL CHIP
J 0
(5940 2650);
DISPLAY 0.489362 (5940 2650);
PAINT SKYBLUE (5940 2650);
FORCEPROP 1 LAST PACK_TYPE 0402LF
J 0
(5950 2600);
DISPLAY 0.489362 (5950 2600);
PAINT SKYBLUE (5950 2600);
FORCEPROP 2 LAST CDS_LIB pure_quanta
J 0
(5900 2725);
DISPLAY INVISIBLE (5900 2725);
FORCEPROP 1 LAST PATH I52
J 0
(5950 2900);
DISPLAY 0.978723 (5950 2900);
PAINT WHITE (5950 2900);
DISPLAY INVISIBLE (5950 2900);
FORCEPROP 1 LAST PART_NUMBER CS21002FB06
J 0
(5940 2600);
DISPLAY 0.489362 (5940 2600);
PAINT SKYBLUE (5940 2600);
DISPLAY INVISIBLE (5940 2600);
FORCEADD Q_RES..2
(6225 2725);
FORCEPROP 1 LAST LOCATION R362
J 0
(6270 2850);
DISPLAY 0.489362 (6270 2850);
PAINT SKYBLUE (6270 2850);
FORCEPROP 0 LAST $SEC 1
J 0
(6275 2900);
DISPLAY 0.680851 (6275 2900);
PAINT MONO (6275 2900);
DISPLAY INVISIBLE (6275 2900);
FORCEPROP 0 LAST CDS_SEC 1
J 0
(6275 2900);
DISPLAY 1.021277 (6275 2900);
DISPLAY INVISIBLE (6275 2900);
FORCEPROP 1 LASTPIN (6225 2825) $PN 1
J 0
(6230 2787);
DISPLAY 0.489362 (6230 2787);
PAINT MONO (6230 2787);
FORCEPROP 1 LASTPIN (6225 2625) $PN 2
J 0
(6230 2635);
DISPLAY 0.489362 (6230 2635);
PAINT MONO (6230 2635);
FORCEPROP 1 LAST WATTAGE 1/16W
J 0
(6265 2700);
DISPLAY 0.489362 (6265 2700);
PAINT SKYBLUE (6265 2700);
FORCEPROP 1 LAST MATERIAL CHIP
J 0
(6265 2650);
DISPLAY 0.489362 (6265 2650);
PAINT SKYBLUE (6265 2650);
FORCEPROP 1 LAST PACK_TYPE 0402LF
J 0
(6275 2600);
DISPLAY 0.489362 (6275 2600);
PAINT SKYBLUE (6275 2600);
FORCEPROP 1 LAST TOLERANCE 1%
J 0
(6270 2750);
DISPLAY 0.489362 (6270 2750);
PAINT SKYBLUE (6270 2750);
FORCEPROP 1 LAST VALUE 1K
J 0
(6270 2800);
DISPLAY 0.489362 (6270 2800);
PAINT SKYBLUE (6270 2800);
FORCEPROP 2 LAST CDS_LIB pure_quanta
J 0
(6225 2725);
DISPLAY INVISIBLE (6225 2725);
FORCEPROP 1 LAST PATH I53
J 0
(6275 2900);
DISPLAY 0.978723 (6275 2900);
PAINT WHITE (6275 2900);
DISPLAY INVISIBLE (6275 2900);
FORCEPROP 1 LAST PART_NUMBER CS21002FB06
J 0
(6265 2600);
DISPLAY 0.489362 (6265 2600);
PAINT SKYBLUE (6265 2600);
DISPLAY INVISIBLE (6265 2600);
FORCEADD Q_RES..2
(6525 2725);
FORCEPROP 1 LAST LOCATION R366
J 0
(6570 2850);
DISPLAY 0.489362 (6570 2850);
PAINT SKYBLUE (6570 2850);
FORCEPROP 0 LAST $SEC 1
J 0
(6575 2900);
DISPLAY 0.680851 (6575 2900);
PAINT MONO (6575 2900);
DISPLAY INVISIBLE (6575 2900);
FORCEPROP 0 LAST CDS_SEC 1
J 0
(6575 2900);
DISPLAY 1.021277 (6575 2900);
DISPLAY INVISIBLE (6575 2900);
FORCEPROP 1 LASTPIN (6525 2825) $PN 1
J 0
(6530 2787);
DISPLAY 0.489362 (6530 2787);
PAINT MONO (6530 2787);
FORCEPROP 1 LASTPIN (6525 2625) $PN 2
J 0
(6530 2635);
DISPLAY 0.489362 (6530 2635);
PAINT MONO (6530 2635);
FORCEPROP 1 LAST MATERIAL CHIP
J 0
(6565 2650);
DISPLAY 0.489362 (6565 2650);
PAINT SKYBLUE (6565 2650);
FORCEPROP 1 LAST PACK_TYPE 0402LF
J 0
(6575 2600);
DISPLAY 0.489362 (6575 2600);
PAINT SKYBLUE (6575 2600);
FORCEPROP 1 LAST WATTAGE 1/16W
J 0
(6565 2700);
DISPLAY 0.489362 (6565 2700);
PAINT SKYBLUE (6565 2700);
FORCEPROP 1 LAST TOLERANCE 1%
J 0
(6570 2750);
DISPLAY 0.489362 (6570 2750);
PAINT SKYBLUE (6570 2750);
FORCEPROP 1 LAST VALUE 1K
J 0
(6570 2800);
DISPLAY 0.489362 (6570 2800);
PAINT SKYBLUE (6570 2800);
FORCEPROP 2 LAST CDS_LIB pure_quanta
J 0
(6525 2725);
DISPLAY INVISIBLE (6525 2725);
FORCEPROP 1 LAST PATH I54
J 0
(6575 2900);
DISPLAY 0.978723 (6575 2900);
PAINT WHITE (6575 2900);
DISPLAY INVISIBLE (6575 2900);
FORCEPROP 1 LAST PART_NUMBER CS21002FB06
J 0
(6565 2600);
DISPLAY 0.489362 (6565 2600);
PAINT SKYBLUE (6565 2600);
DISPLAY INVISIBLE (6565 2600);
FORCEADD Q_RES..2
(5925 3650);
FORCEPROP 1 LAST LOCATION R360
J 0
(5970 3775);
DISPLAY 0.489362 (5970 3775);
PAINT SKYBLUE (5970 3775);
FORCEPROP 0 LAST $SEC 1
J 0
(5975 3825);
DISPLAY 0.680851 (5975 3825);
PAINT MONO (5975 3825);
DISPLAY INVISIBLE (5975 3825);
FORCEPROP 0 LAST CDS_SEC 1
J 0
(5975 3825);
DISPLAY 1.021277 (5975 3825);
DISPLAY INVISIBLE (5975 3825);
FORCEPROP 1 LASTPIN (5925 3750) $PN 1
J 0
(5930 3712);
DISPLAY 0.489362 (5930 3712);
PAINT MONO (5930 3712);
FORCEPROP 1 LASTPIN (5925 3550) $PN 2
J 0
(5930 3560);
DISPLAY 0.489362 (5930 3560);
PAINT MONO (5930 3560);
FORCEPROP 1 LAST WATTAGE 1/16W
J 0
(5965 3625);
DISPLAY 0.489362 (5965 3625);
PAINT SKYBLUE (5965 3625);
FORCEPROP 1 LAST MATERIAL CHIP
J 0
(5965 3575);
DISPLAY 0.489362 (5965 3575);
PAINT SKYBLUE (5965 3575);
FORCEPROP 1 LAST PACK_TYPE 0402LF
J 0
(5975 3525);
DISPLAY 0.489362 (5975 3525);
PAINT SKYBLUE (5975 3525);
FORCEPROP 1 LAST TOLERANCE 1%
J 0
(5970 3675);
DISPLAY 0.489362 (5970 3675);
PAINT SKYBLUE (5970 3675);
FORCEPROP 1 LAST VALUE 1K
J 0
(5970 3725);
DISPLAY 0.489362 (5970 3725);
PAINT SKYBLUE (5970 3725);
FORCEPROP 2 LAST CDS_LIB pure_quanta
J 0
(5925 3650);
DISPLAY INVISIBLE (5925 3650);
FORCEPROP 1 LAST PATH I55
J 0
(5975 3825);
DISPLAY 0.978723 (5975 3825);
PAINT WHITE (5975 3825);
DISPLAY INVISIBLE (5975 3825);
FORCEPROP 1 LAST PART_NUMBER CS21002FB06
J 0
(5965 3525);
DISPLAY 0.489362 (5965 3525);
PAINT SKYBLUE (5965 3525);
DISPLAY INVISIBLE (5965 3525);
FORCEADD Q_RES..2
(6250 3650);
FORCEPROP 1 LAST LOCATION R363
J 0
(6295 3775);
DISPLAY 0.489362 (6295 3775);
PAINT SKYBLUE (6295 3775);
FORCEPROP 0 LAST $SEC 1
J 0
(6300 3825);
DISPLAY 0.680851 (6300 3825);
PAINT MONO (6300 3825);
DISPLAY INVISIBLE (6300 3825);
FORCEPROP 0 LAST CDS_SEC 1
J 0
(6300 3825);
DISPLAY 1.021277 (6300 3825);
DISPLAY INVISIBLE (6300 3825);
FORCEPROP 1 LASTPIN (6250 3750) $PN 1
J 0
(6255 3712);
DISPLAY 0.489362 (6255 3712);
PAINT MONO (6255 3712);
FORCEPROP 1 LASTPIN (6250 3550) $PN 2
J 0
(6255 3560);
DISPLAY 0.489362 (6255 3560);
PAINT MONO (6255 3560);
FORCEPROP 1 LAST WATTAGE 1/16W
J 0
(6290 3625);
DISPLAY 0.489362 (6290 3625);
PAINT SKYBLUE (6290 3625);
FORCEPROP 1 LAST TOLERANCE 1%
J 0
(6295 3675);
DISPLAY 0.489362 (6295 3675);
PAINT SKYBLUE (6295 3675);
FORCEPROP 1 LAST MATERIAL CHIP
J 0
(6290 3575);
DISPLAY 0.489362 (6290 3575);
PAINT SKYBLUE (6290 3575);
FORCEPROP 1 LAST VALUE 1K
J 0
(6295 3725);
DISPLAY 0.489362 (6295 3725);
PAINT SKYBLUE (6295 3725);
FORCEPROP 1 LAST PACK_TYPE 0402LF
J 0
(6300 3525);
DISPLAY 0.489362 (6300 3525);
PAINT SKYBLUE (6300 3525);
FORCEPROP 2 LAST CDS_LIB pure_quanta
J 0
(6250 3650);
DISPLAY INVISIBLE (6250 3650);
FORCEPROP 1 LAST PATH I56
J 0
(6300 3825);
DISPLAY 0.978723 (6300 3825);
PAINT WHITE (6300 3825);
DISPLAY INVISIBLE (6300 3825);
FORCEPROP 1 LAST PART_NUMBER CS21002FB06
J 0
(6290 3525);
DISPLAY 0.489362 (6290 3525);
PAINT SKYBLUE (6290 3525);
DISPLAY INVISIBLE (6290 3525);
FORCEADD Q_RES..2
(6550 3650);
FORCEPROP 1 LAST LOCATION R367
J 0
(6595 3775);
DISPLAY 0.489362 (6595 3775);
PAINT SKYBLUE (6595 3775);
FORCEPROP 0 LAST $SEC 1
J 0
(6600 3825);
DISPLAY 0.680851 (6600 3825);
PAINT MONO (6600 3825);
DISPLAY INVISIBLE (6600 3825);
FORCEPROP 0 LAST CDS_SEC 1
J 0
(6600 3825);
DISPLAY 1.021277 (6600 3825);
DISPLAY INVISIBLE (6600 3825);
FORCEPROP 1 LASTPIN (6550 3750) $PN 1
J 0
(6555 3712);
DISPLAY 0.489362 (6555 3712);
PAINT MONO (6555 3712);
FORCEPROP 1 LASTPIN (6550 3550) $PN 2
J 0
(6555 3560);
DISPLAY 0.489362 (6555 3560);
PAINT MONO (6555 3560);
FORCEPROP 1 LAST VALUE 1K
J 0
(6595 3725);
DISPLAY 0.489362 (6595 3725);
PAINT SKYBLUE (6595 3725);
FORCEPROP 1 LAST WATTAGE 1/16W
J 0
(6590 3625);
DISPLAY 0.489362 (6590 3625);
PAINT SKYBLUE (6590 3625);
FORCEPROP 1 LAST MATERIAL CHIP
J 0
(6590 3575);
DISPLAY 0.489362 (6590 3575);
PAINT SKYBLUE (6590 3575);
FORCEPROP 1 LAST TOLERANCE 1%
J 0
(6595 3675);
DISPLAY 0.489362 (6595 3675);
PAINT SKYBLUE (6595 3675);
FORCEPROP 1 LAST PACK_TYPE 0402LF
J 0
(6600 3525);
DISPLAY 0.489362 (6600 3525);
PAINT SKYBLUE (6600 3525);
FORCEPROP 2 LAST CDS_LIB pure_quanta
J 0
(6550 3650);
DISPLAY INVISIBLE (6550 3650);
FORCEPROP 1 LAST PATH I57
J 0
(6600 3825);
DISPLAY 0.978723 (6600 3825);
PAINT WHITE (6600 3825);
DISPLAY INVISIBLE (6600 3825);
FORCEPROP 1 LAST PART_NUMBER CS21002FB06
J 0
(6590 3525);
DISPLAY 0.489362 (6590 3525);
PAINT SKYBLUE (6590 3525);
DISPLAY INVISIBLE (6590 3525);
FORCEADD Q_RES..2
(6850 2725);
FORCEPROP 1 LAST LOCATION R369
J 0
(6895 2850);
DISPLAY 0.489362 (6895 2850);
PAINT SKYBLUE (6895 2850);
FORCEPROP 0 LAST $SEC 1
J 0
(6900 2900);
DISPLAY 0.680851 (6900 2900);
PAINT MONO (6900 2900);
DISPLAY INVISIBLE (6900 2900);
FORCEPROP 0 LAST CDS_SEC 1
J 0
(6900 2900);
DISPLAY 1.021277 (6900 2900);
DISPLAY INVISIBLE (6900 2900);
FORCEPROP 1 LASTPIN (6850 2825) $PN 1
J 0
(6855 2787);
DISPLAY 0.489362 (6855 2787);
PAINT MONO (6855 2787);
FORCEPROP 1 LASTPIN (6850 2625) $PN 2
J 0
(6855 2635);
DISPLAY 0.489362 (6855 2635);
PAINT MONO (6855 2635);
FORCEPROP 1 LAST PACK_TYPE 0402LF
J 0
(6900 2600);
DISPLAY 0.489362 (6900 2600);
PAINT SKYBLUE (6900 2600);
FORCEPROP 1 LAST MATERIAL CHIP
J 0
(6890 2650);
DISPLAY 0.489362 (6890 2650);
PAINT SKYBLUE (6890 2650);
FORCEPROP 1 LAST WATTAGE 1/16W
J 0
(6890 2700);
DISPLAY 0.489362 (6890 2700);
PAINT SKYBLUE (6890 2700);
FORCEPROP 1 LAST VALUE 1K
J 0
(6895 2800);
DISPLAY 0.489362 (6895 2800);
PAINT SKYBLUE (6895 2800);
FORCEPROP 1 LAST TOLERANCE 1%
J 0
(6895 2750);
DISPLAY 0.489362 (6895 2750);
PAINT SKYBLUE (6895 2750);
FORCEPROP 2 LAST CDS_LIB pure_quanta
J 0
(6850 2725);
DISPLAY INVISIBLE (6850 2725);
FORCEPROP 1 LAST PATH I58
J 0
(6900 2900);
DISPLAY 0.978723 (6900 2900);
PAINT WHITE (6900 2900);
DISPLAY INVISIBLE (6900 2900);
FORCEPROP 1 LAST PART_NUMBER CS21002FB06
J 0
(6890 2600);
DISPLAY 0.489362 (6890 2600);
PAINT SKYBLUE (6890 2600);
DISPLAY INVISIBLE (6890 2600);
FORCEADD VCC_CORE..1
(6225 3050);
FORCEPROP 3 LASTPIN (6225 3000) SIG_NAME PVDD11_S3_P1\g
J 0
(6235 3010);
DISPLAY 0.659574 (6235 3010);
PAINT MONO (6235 3010);
DISPLAY INVISIBLE (6235 3010);
FORCEPROP 1 LAST HDL_POWER PVDD11_S3_P1
J 1
(6225 3100);
DISPLAY 0.489362 (6225 3100);
PAINT GREEN (6225 3100);
FORCEPROP 2 LAST CDS_LIB pure_quanta_power
J 0
(6225 3050);
DISPLAY INVISIBLE (6225 3050);
FORCEPROP 1 LAST PATH I59
J 0
(6275 3075);
DISPLAY 0.872340 (6275 3075);
PAINT AQUA (6275 3075);
DISPLAY INVISIBLE (6275 3075);
FORCEADD Q_RES..1
(1725 1100);
FORCEPROP 1 LAST LOCATION R148
J 0
(1225 1100);
DISPLAY 0.489362 (1225 1100);
PAINT SKYBLUE (1225 1100);
FORCEPROP 0 LAST $SEC 1
J 0
(1825 1150);
DISPLAY 0.680851 (1825 1150);
PAINT MONO (1825 1150);
DISPLAY INVISIBLE (1825 1150);
FORCEPROP 0 LAST CDS_SEC 1
J 0
(1825 1150);
DISPLAY 1.021277 (1825 1150);
DISPLAY INVISIBLE (1825 1150);
FORCEPROP 1 LASTPIN (1625 1100) $PN 1
J 0
(1637 1112);
DISPLAY 0.489362 (1637 1112);
PAINT MONO (1637 1112);
FORCEPROP 1 LASTPIN (1825 1100) $PN 2
J 0
(1787 1112);
DISPLAY 0.489362 (1787 1112);
PAINT MONO (1787 1112);
FORCEPROP 1 LAST VALUE 0
J 2
(1825 1125);
DISPLAY 0.489362 (1825 1125);
PAINT SKYBLUE (1825 1125);
FORCEPROP 1 LAST MATERIAL EMPTY
J 0
(1425 1125);
DISPLAY 0.489362 (1425 1125);
PAINT RED (1425 1125);
FORCEPROP 2 LAST CDS_LIB pure_quanta
J 0
(1725 1100);
DISPLAY INVISIBLE (1725 1100);
FORCEPROP 1 LAST WATTAGE 1/16W
J 2
(1700 950);
DISPLAY 0.510638 (1700 950);
PAINT SKYBLUE (1700 950);
DISPLAY INVISIBLE (1700 950);
FORCEPROP 1 LAST TOLERANCE 5%
J 0
(1725 1000);
DISPLAY 0.510638 (1725 1000);
PAINT SKYBLUE (1725 1000);
DISPLAY INVISIBLE (1725 1000);
FORCEPROP 1 LAST PACK_TYPE 0402LF
J 0
(1725 1050);
DISPLAY 0.510638 (1725 1050);
PAINT SKYBLUE (1725 1050);
DISPLAY INVISIBLE (1725 1050);
FORCEPROP 1 LAST PATH I6
J 0
(1675 1250);
DISPLAY 0.978723 (1675 1250);
PAINT WHITE (1675 1250);
DISPLAY INVISIBLE (1675 1250);
FORCEPROP 1 LAST PART_NUMBER CS00002JB13
J 0
(1675 1200);
DISPLAY 0.510638 (1675 1200);
PAINT SKYBLUE (1675 1200);
DISPLAY INVISIBLE (1675 1200);
FORCEADD Q_RES..2
(6875 3650);
FORCEPROP 1 LAST LOCATION R370
J 0
(6920 3775);
DISPLAY 0.489362 (6920 3775);
PAINT SKYBLUE (6920 3775);
FORCEPROP 0 LAST $SEC 1
J 0
(6925 3825);
DISPLAY 0.680851 (6925 3825);
PAINT MONO (6925 3825);
DISPLAY INVISIBLE (6925 3825);
FORCEPROP 0 LAST CDS_SEC 1
J 0
(6925 3825);
DISPLAY 1.021277 (6925 3825);
DISPLAY INVISIBLE (6925 3825);
FORCEPROP 1 LASTPIN (6875 3750) $PN 1
J 0
(6880 3712);
DISPLAY 0.489362 (6880 3712);
PAINT MONO (6880 3712);
FORCEPROP 1 LASTPIN (6875 3550) $PN 2
J 0
(6880 3560);
DISPLAY 0.489362 (6880 3560);
PAINT MONO (6880 3560);
FORCEPROP 1 LAST PACK_TYPE 0402LF
J 0
(6925 3525);
DISPLAY 0.489362 (6925 3525);
PAINT SKYBLUE (6925 3525);
FORCEPROP 1 LAST WATTAGE 1/16W
J 0
(6915 3625);
DISPLAY 0.489362 (6915 3625);
PAINT SKYBLUE (6915 3625);
FORCEPROP 1 LAST TOLERANCE 1%
J 0
(6920 3675);
DISPLAY 0.489362 (6920 3675);
PAINT SKYBLUE (6920 3675);
FORCEPROP 1 LAST VALUE 1K
J 0
(6920 3725);
DISPLAY 0.489362 (6920 3725);
PAINT SKYBLUE (6920 3725);
FORCEPROP 1 LAST MATERIAL CHIP
J 0
(6915 3575);
DISPLAY 0.489362 (6915 3575);
PAINT SKYBLUE (6915 3575);
FORCEPROP 2 LAST CDS_LIB pure_quanta
J 0
(6875 3650);
DISPLAY INVISIBLE (6875 3650);
FORCEPROP 1 LAST PATH I60
J 0
(6925 3825);
DISPLAY 0.978723 (6925 3825);
PAINT WHITE (6925 3825);
DISPLAY INVISIBLE (6925 3825);
FORCEPROP 1 LAST PART_NUMBER CS21002FB06
J 0
(6915 3525);
DISPLAY 0.489362 (6915 3525);
PAINT SKYBLUE (6915 3525);
DISPLAY INVISIBLE (6915 3525);
FORCEADD OFFPAGE..2
(4025 3825);
FORCEPROP 2 LAST $XR1 54 
J 0
(4334 3825);
DISPLAY 0.638298 (4334 3825);
PAINT MONO (4334 3825);
FORCEPROP 2 LAST $XR0 161 
J 0
(4214 3825);
DISPLAY 0.638298 (4214 3825);
PAINT MONO (4214 3825);
FORCEPROP 2 LAST CDS_LIB standard
J 0
(4025 3825);
DISPLAY INVISIBLE (4025 3825);
FORCEPROP 1 LAST OFFPAGE TRUE
J 0
(4350 3700);
DISPLAY 0.872340 (4350 3700);
PAINT GREEN (4350 3700);
DISPLAY INVISIBLE (4350 3700);
FORCEPROP 1 LAST COMMENT_BODY TRUE
J 0
(3980 3730);
DISPLAY 0.872340 (3980 3730);
PAINT GREEN (3980 3730);
DISPLAY INVISIBLE (3980 3730);
FORCEPROP 2 LAST PATH I61
J 0
(4325 3875);
DISPLAY 0.680851 (4325 3875);
DISPLAY INVISIBLE (4325 3875);
FORCEADD OFFPAGE..3
(4025 3875);
FORCEPROP 2 LAST $XR1 54 
J 0
(4359 3875);
DISPLAY 0.638298 (4359 3875);
PAINT MONO (4359 3875);
FORCEPROP 2 LAST $XR0 161 
J 0
(4239 3875);
DISPLAY 0.638298 (4239 3875);
PAINT MONO (4239 3875);
FORCEPROP 2 LAST CDS_LIB standard
J 0
(4025 3875);
DISPLAY INVISIBLE (4025 3875);
FORCEPROP 1 LAST OFFPAGE TRUE
J 0
(4350 3750);
DISPLAY 0.872340 (4350 3750);
PAINT GREEN (4350 3750);
DISPLAY INVISIBLE (4350 3750);
FORCEPROP 1 LAST COMMENT_BODY TRUE
J 0
(3975 3775);
DISPLAY 0.872340 (3975 3775);
PAINT PEACH (3975 3775);
DISPLAY INVISIBLE (3975 3775);
FORCEPROP 2 LAST PATH I62
J 0
(4375 3925);
DISPLAY 0.680851 (4375 3925);
DISPLAY INVISIBLE (4375 3925);
FORCEADD OFFPAGE..2
(4025 3975);
FORCEPROP 2 LAST $XR1 27 
J 0
(4334 3975);
DISPLAY 0.638298 (4334 3975);
PAINT MONO (4334 3975);
FORCEPROP 2 LAST $XR0 161 
J 0
(4214 3975);
DISPLAY 0.638298 (4214 3975);
PAINT MONO (4214 3975);
FORCEPROP 2 LAST CDS_LIB standard
J 0
(4025 3975);
DISPLAY INVISIBLE (4025 3975);
FORCEPROP 1 LAST OFFPAGE TRUE
J 0
(4350 3850);
DISPLAY 0.872340 (4350 3850);
PAINT GREEN (4350 3850);
DISPLAY INVISIBLE (4350 3850);
FORCEPROP 1 LAST COMMENT_BODY TRUE
J 0
(3980 3880);
DISPLAY 0.872340 (3980 3880);
PAINT GREEN (3980 3880);
DISPLAY INVISIBLE (3980 3880);
FORCEPROP 2 LAST PATH I63
J 0
(4350 4025);
DISPLAY 0.680851 (4350 4025);
DISPLAY INVISIBLE (4350 4025);
FORCEADD OFFPAGE..3
(4025 4025);
FORCEPROP 2 LAST $XR1 27 
J 0
(4359 4025);
DISPLAY 0.638298 (4359 4025);
PAINT MONO (4359 4025);
FORCEPROP 2 LAST $XR0 161 
J 0
(4239 4025);
DISPLAY 0.638298 (4239 4025);
PAINT MONO (4239 4025);
FORCEPROP 2 LAST CDS_LIB standard
J 0
(4025 4025);
DISPLAY INVISIBLE (4025 4025);
FORCEPROP 1 LAST OFFPAGE TRUE
J 0
(4350 3900);
DISPLAY 0.872340 (4350 3900);
PAINT GREEN (4350 3900);
DISPLAY INVISIBLE (4350 3900);
FORCEPROP 1 LAST COMMENT_BODY TRUE
J 0
(3975 3925);
DISPLAY 0.872340 (3975 3925);
PAINT PEACH (3975 3925);
DISPLAY INVISIBLE (3975 3925);
FORCEPROP 2 LAST PATH I64
J 0
(4375 4075);
DISPLAY 0.680851 (4375 4075);
DISPLAY INVISIBLE (4375 4075);
FORCEADD VCC_CORE..1
(6250 3975);
FORCEPROP 3 LASTPIN (6250 3925) SIG_NAME PVDD11_S3_P0\g
J 0
(6260 3935);
DISPLAY 0.659574 (6260 3935);
PAINT MONO (6260 3935);
DISPLAY INVISIBLE (6260 3935);
FORCEPROP 1 LAST HDL_POWER PVDD11_S3_P0
J 1
(6250 4025);
DISPLAY 0.489362 (6250 4025);
PAINT GREEN (6250 4025);
FORCEPROP 2 LAST CDS_LIB pure_quanta_power
J 0
(6250 3975);
DISPLAY INVISIBLE (6250 3975);
FORCEPROP 1 LAST PATH I65
J 0
(6300 4000);
DISPLAY 0.872340 (6300 4000);
PAINT AQUA (6300 4000);
DISPLAY INVISIBLE (6300 4000);
FORCEADD PI3CSW12ZUAEX..1
R 2
(1625 1925);
FORCEPROP 1 LAST LOCATION U6
J 2
(1769 2268);
DISPLAY 0.723404 (1769 2268);
PAINT GREEN (1769 2268);
FORCEPROP 2 LAST SEC 1
J 0
(1750 2425);
DISPLAY 0.680851 (1750 2425);
PAINT MONO (1750 2425);
DISPLAY INVISIBLE (1750 2425);
FORCEPROP 2 LASTPIN (1925 1925) $PN 1
J 0
(1935 1935);
DISPLAY 0.680851 (1935 1935);
PAINT MONO (1935 1935);
FORCEPROP 2 LASTPIN (1925 1875) $PN 2
J 0
(1935 1885);
DISPLAY 0.680851 (1935 1885);
PAINT MONO (1935 1885);
FORCEPROP 2 LASTPIN (1925 1825) $PN 3
J 0
(1935 1835);
DISPLAY 0.680851 (1935 1835);
PAINT MONO (1935 1835);
FORCEPROP 2 LASTPIN (1925 1775) $PN 4
J 0
(1935 1785);
DISPLAY 0.680851 (1935 1785);
PAINT MONO (1935 1785);
FORCEPROP 2 LASTPIN (1325 2025) $PN 8
J 2
(1315 2035);
DISPLAY 0.680851 (1315 2035);
PAINT MONO (1315 2035);
FORCEPROP 2 LASTPIN (1325 1975) $PN 7
J 2
(1315 1985);
DISPLAY 0.680851 (1315 1985);
PAINT MONO (1315 1985);
FORCEPROP 2 LASTPIN (1325 1775) $PN 5
J 2
(1315 1785);
DISPLAY 0.680851 (1315 1785);
PAINT MONO (1315 1785);
FORCEPROP 2 LASTPIN (1925 2075) $PN 6
J 0
(1935 2085);
DISPLAY 0.680851 (1935 2085);
PAINT MONO (1935 2085);
FORCEPROP 2 LASTPIN (1925 2025) $PN 9
J 0
(1935 2035);
DISPLAY 0.680851 (1935 2035);
PAINT MONO (1935 2035);
FORCEPROP 2 LASTPIN (1325 2075) $PN 10
J 2
(1315 2085);
DISPLAY 0.680851 (1315 2085);
PAINT MONO (1315 2085);
FORCEPROP 1 LAST MATERIAL IC
J 2
(1769 2144);
DISPLAY 0.723404 (1769 2144);
PAINT GREEN (1769 2144);
FORCEPROP 2 LAST PART_TYPE SMLF
J 2
(1750 2375);
DISPLAY 0.680851 (1750 2375);
FORCEPROP 2 LAST VALUE PI3CSW12ZUAEX
J 2
(1750 2325);
DISPLAY 0.680851 (1750 2325);
FORCEPROP 1 LAST NEEDS_NO_SIZE TRUE
J 2
(1625 1925);
DISPLAY 0.723404 (1625 1925);
PAINT GREEN (1625 1925);
DISPLAY INVISIBLE (1625 1925);
FORCEPROP 2 LAST SEC_TYPE 
J 0
(1750 2425);
DISPLAY 0.680851 (1750 2425);
DISPLAY INVISIBLE (1750 2425);
FORCEPROP 1 LAST CDS_LMAN_SYM_OUTLINE -150,200,150,-200
J 2
(1625 1925);
DISPLAY 0.468085 (1625 1925);
PAINT GREEN (1625 1925);
DISPLAY INVISIBLE (1625 1925);
FORCEPROP 2 LAST CDS_LIB pure_quanta
J 2
(1625 1925);
DISPLAY INVISIBLE (1625 1925);
FORCEPROP 1 LAST PATH I67
J 2
(1625 1925);
DISPLAY 0.723404 (1625 1925);
PAINT GREEN (1625 1925);
DISPLAY INVISIBLE (1625 1925);
FORCEPROP 1 LAST PART_NUMBER AL3CSW12000
J 2
(1763 2214);
DISPLAY 0.723404 (1763 2214);
PAINT GREEN (1763 2214);
DISPLAY INVISIBLE (1763 2214);
FORCEADD Q_CAP..1
(750 2350);
FORCEPROP 1 LAST LOCATION C25
J 0
(800 2450);
DISPLAY 0.638298 (800 2450);
FORCEPROP 0 LAST $SEC 1
J 0
(800 2500);
DISPLAY 0.680851 (800 2500);
PAINT MONO (800 2500);
DISPLAY INVISIBLE (800 2500);
FORCEPROP 0 LAST CDS_SEC 1
J 0
(800 2500);
DISPLAY 0.680851 (800 2500);
DISPLAY INVISIBLE (800 2500);
FORCEPROP 1 LASTPIN (750 2450) $PN 1
J 0
(760 2430);
DISPLAY 0.787234 (760 2430);
PAINT MONO (760 2430);
FORCEPROP 1 LASTPIN (750 2250) $PN 2
J 0
(760 2230);
DISPLAY 0.787234 (760 2230);
PAINT MONO (760 2230);
FORCEPROP 1 LAST TOLERANCE 10%
J 0
(800 2300);
DISPLAY 0.638298 (800 2300);
FORCEPROP 1 LAST VOLTAGE 25V
J 0
(800 2350);
DISPLAY 0.638298 (800 2350);
FORCEPROP 1 LAST PACK_TYPE 0402
J 0
(800 2150);
DISPLAY 0.638298 (800 2150);
FORCEPROP 1 LAST VALUE 0.1UF
J 0
(800 2400);
DISPLAY 0.638298 (800 2400);
FORCEPROP 1 LAST MATERIAL X7R
J 0
(800 2250);
DISPLAY 0.638298 (800 2250);
FORCEPROP 2 LAST CDS_LIB pure_quanta
J 0
(750 2350);
DISPLAY INVISIBLE (750 2350);
FORCEPROP 1 LAST PATH I69
J 0
(800 2500);
DISPLAY 0.978723 (800 2500);
PAINT WHITE (800 2500);
DISPLAY INVISIBLE (800 2500);
FORCEPROP 1 LAST PART_NUMBER CH4104K1B00
J 0
(800 2200);
DISPLAY 0.638298 (800 2200);
DISPLAY INVISIBLE (800 2200);
FORCEADD UNIVERSAL_GND..1
(750 2150);
FORCEPROP 3 LASTPIN (750 2200) SIG_NAME GND\g
J 0
(760 2210);
DISPLAY 0.659574 (760 2210);
PAINT MONO (760 2210);
DISPLAY INVISIBLE (760 2210);
FORCEPROP 2 LAST CDS_LIB pure_quanta_power
J 0
(750 2150);
DISPLAY INVISIBLE (750 2150);
FORCEPROP 1 LAST HDL_POWER GND
J 1
(775 2075);
DISPLAY 0.872340 (775 2075);
PAINT GREEN (775 2075);
DISPLAY INVISIBLE (775 2075);
FORCEPROP 1 LAST PATH I70
J 0
(825 2150);
DISPLAY 0.872340 (825 2150);
PAINT AQUA (825 2150);
DISPLAY INVISIBLE (825 2150);
FORCEADD OFFPAGE..3
(4050 1875);
FORCEPROP 2 LAST $XR1 161 
J 0
(4354 1875);
DISPLAY 0.638298 (4354 1875);
PAINT MONO (4354 1875);
FORCEPROP 2 LAST $XR0 28 
J 0
(4264 1875);
DISPLAY 0.638298 (4264 1875);
PAINT MONO (4264 1875);
FORCEPROP 2 LAST CDS_LIB standard
J 0
(4050 1875);
DISPLAY INVISIBLE (4050 1875);
FORCEPROP 1 LAST OFFPAGE TRUE
J 0
(4375 1750);
DISPLAY 0.872340 (4375 1750);
PAINT GREEN (4375 1750);
DISPLAY INVISIBLE (4375 1750);
FORCEPROP 1 LAST COMMENT_BODY TRUE
J 0
(4000 1775);
DISPLAY 0.872340 (4000 1775);
PAINT PEACH (4000 1775);
DISPLAY INVISIBLE (4000 1775);
FORCEPROP 2 LAST PATH I71
J 0
(4250 1950);
DISPLAY 0.680851 (4250 1950);
DISPLAY INVISIBLE (4250 1950);
FORCEADD OFFPAGE..3
(4050 1775);
FORCEPROP 2 LAST $XR1 161 
J 0
(4354 1775);
DISPLAY 0.638298 (4354 1775);
PAINT MONO (4354 1775);
FORCEPROP 2 LAST $XR0 55 
J 0
(4264 1775);
DISPLAY 0.638298 (4264 1775);
PAINT MONO (4264 1775);
FORCEPROP 2 LAST CDS_LIB standard
J 0
(4050 1775);
DISPLAY INVISIBLE (4050 1775);
FORCEPROP 1 LAST OFFPAGE TRUE
J 0
(4375 1650);
DISPLAY 0.872340 (4375 1650);
PAINT GREEN (4375 1650);
DISPLAY INVISIBLE (4375 1650);
FORCEPROP 1 LAST COMMENT_BODY TRUE
J 0
(4000 1675);
DISPLAY 0.872340 (4000 1675);
PAINT PEACH (4000 1675);
DISPLAY INVISIBLE (4000 1675);
FORCEPROP 2 LAST PATH I72
J 0
(4250 1850);
DISPLAY 0.680851 (4250 1850);
DISPLAY INVISIBLE (4250 1850);
FORCEADD Q_RES..1
(3150 3825);
FORCEPROP 1 LAST LOCATION R1158
J 0
(2950 3825);
DISPLAY 0.489362 (2950 3825);
PAINT SKYBLUE (2950 3825);
FORCEPROP 0 LAST $SEC 1
J 0
(3350 3850);
DISPLAY 0.680851 (3350 3850);
PAINT MONO (3350 3850);
DISPLAY INVISIBLE (3350 3850);
FORCEPROP 0 LAST CDS_SEC 1
J 0
(3350 3850);
DISPLAY 0.680851 (3350 3850);
DISPLAY INVISIBLE (3350 3850);
FORCEPROP 1 LASTPIN (3050 3825) $PN 1
J 0
(3062 3837);
DISPLAY 0.787234 (3062 3837);
PAINT MONO (3062 3837);
FORCEPROP 1 LASTPIN (3250 3825) $PN 2
J 0
(3212 3837);
DISPLAY 0.787234 (3212 3837);
PAINT MONO (3212 3837);
FORCEPROP 1 LAST MATERIAL EMPTY
J 0
(2825 3825);
DISPLAY 0.489362 (2825 3825);
PAINT RED (2825 3825);
FORCEPROP 1 LAST VALUE 33
J 2
(3350 3825);
DISPLAY 0.617021 (3350 3825);
PAINT SKYBLUE (3350 3825);
FORCEPROP 1 LAST PACK_TYPE 0402LF
J 0
(3200 3750);
DISPLAY 0.489362 (3200 3750);
PAINT SKYBLUE (3200 3750);
DISPLAY INVISIBLE (3200 3750);
FORCEPROP 1 LAST TOLERANCE 5%
J 0
(3125 3750);
DISPLAY 0.489362 (3125 3750);
PAINT SKYBLUE (3125 3750);
DISPLAY INVISIBLE (3125 3750);
FORCEPROP 1 LAST WATTAGE 1/16W
J 2
(3550 3750);
DISPLAY 0.489362 (3550 3750);
PAINT SKYBLUE (3550 3750);
DISPLAY INVISIBLE (3550 3750);
FORCEPROP 2 LAST CDS_LIB pure_quanta
J 0
(3150 3825);
DISPLAY INVISIBLE (3150 3825);
FORCEPROP 1 LAST PATH I73
J 0
(3100 3975);
DISPLAY 0.978723 (3100 3975);
PAINT WHITE (3100 3975);
DISPLAY INVISIBLE (3100 3975);
FORCEPROP 1 LAST PART_NUMBER CS03302JB10
J 0
(3175 3875);
DISPLAY 0.489362 (3175 3875);
PAINT SKYBLUE (3175 3875);
DISPLAY INVISIBLE (3175 3875);
FORCEADD Q_RES..1
(3150 3875);
FORCEPROP 1 LAST LOCATION R1157
J 0
(2950 3875);
DISPLAY 0.489362 (2950 3875);
PAINT SKYBLUE (2950 3875);
FORCEPROP 0 LAST $SEC 1
J 0
(3350 3900);
DISPLAY 0.680851 (3350 3900);
PAINT MONO (3350 3900);
DISPLAY INVISIBLE (3350 3900);
FORCEPROP 0 LAST CDS_SEC 1
J 0
(3350 3900);
DISPLAY 0.680851 (3350 3900);
DISPLAY INVISIBLE (3350 3900);
FORCEPROP 1 LASTPIN (3050 3875) $PN 1
J 0
(3062 3887);
DISPLAY 0.787234 (3062 3887);
PAINT MONO (3062 3887);
FORCEPROP 1 LASTPIN (3250 3875) $PN 2
J 0
(3212 3887);
DISPLAY 0.787234 (3212 3887);
PAINT MONO (3212 3887);
FORCEPROP 1 LAST MATERIAL EMPTY
J 0
(2825 3875);
DISPLAY 0.489362 (2825 3875);
PAINT RED (2825 3875);
FORCEPROP 1 LAST VALUE 33
J 2
(3350 3875);
DISPLAY 0.617021 (3350 3875);
PAINT SKYBLUE (3350 3875);
FORCEPROP 2 LAST CDS_LIB pure_quanta
J 0
(3150 3875);
DISPLAY INVISIBLE (3150 3875);
FORCEPROP 1 LAST PACK_TYPE 0402LF
J 0
(3200 3800);
DISPLAY 0.489362 (3200 3800);
PAINT SKYBLUE (3200 3800);
DISPLAY INVISIBLE (3200 3800);
FORCEPROP 1 LAST TOLERANCE 5%
J 0
(3125 3800);
DISPLAY 0.489362 (3125 3800);
PAINT SKYBLUE (3125 3800);
DISPLAY INVISIBLE (3125 3800);
FORCEPROP 1 LAST WATTAGE 1/16W
J 2
(3550 3800);
DISPLAY 0.489362 (3550 3800);
PAINT SKYBLUE (3550 3800);
DISPLAY INVISIBLE (3550 3800);
FORCEPROP 1 LAST PATH I74
J 0
(3100 4025);
DISPLAY 0.978723 (3100 4025);
PAINT WHITE (3100 4025);
DISPLAY INVISIBLE (3100 4025);
FORCEPROP 1 LAST PART_NUMBER CS03302JB10
J 0
(3175 3925);
DISPLAY 0.489362 (3175 3925);
PAINT SKYBLUE (3175 3925);
DISPLAY INVISIBLE (3175 3925);
FORCEADD Q_RES..1
(3175 1875);
FORCEPROP 1 LAST LOCATION R1160
J 0
(2975 1875);
DISPLAY 0.489362 (2975 1875);
PAINT SKYBLUE (2975 1875);
FORCEPROP 0 LAST $SEC 1
J 0
(3375 1900);
DISPLAY 0.680851 (3375 1900);
PAINT MONO (3375 1900);
DISPLAY INVISIBLE (3375 1900);
FORCEPROP 0 LAST CDS_SEC 1
J 0
(3375 1900);
DISPLAY 0.680851 (3375 1900);
DISPLAY INVISIBLE (3375 1900);
FORCEPROP 1 LASTPIN (3075 1875) $PN 1
J 0
(3087 1887);
DISPLAY 0.787234 (3087 1887);
PAINT MONO (3087 1887);
FORCEPROP 1 LASTPIN (3275 1875) $PN 2
J 0
(3237 1887);
DISPLAY 0.787234 (3237 1887);
PAINT MONO (3237 1887);
FORCEPROP 1 LAST VALUE 0
J 2
(3375 1875);
DISPLAY 0.489362 (3375 1875);
PAINT SKYBLUE (3375 1875);
FORCEPROP 2 LAST CDS_LIB pure_quanta
J 0
(3175 1875);
DISPLAY INVISIBLE (3175 1875);
FORCEPROP 1 LAST PACK_TYPE 0402LF
J 0
(3225 1800);
DISPLAY 0.489362 (3225 1800);
PAINT SKYBLUE (3225 1800);
DISPLAY INVISIBLE (3225 1800);
FORCEPROP 1 LAST TOLERANCE 5%
J 0
(3150 1800);
DISPLAY 0.489362 (3150 1800);
PAINT SKYBLUE (3150 1800);
DISPLAY INVISIBLE (3150 1800);
FORCEPROP 1 LAST MATERIAL CHIP
J 0
(3600 1800);
DISPLAY 0.489362 (3600 1800);
PAINT SKYBLUE (3600 1800);
DISPLAY INVISIBLE (3600 1800);
FORCEPROP 1 LAST WATTAGE 1/16W
J 2
(3575 1800);
DISPLAY 0.489362 (3575 1800);
PAINT SKYBLUE (3575 1800);
DISPLAY INVISIBLE (3575 1800);
FORCEPROP 1 LAST PATH I75
J 0
(3125 2025);
DISPLAY 0.978723 (3125 2025);
PAINT WHITE (3125 2025);
DISPLAY INVISIBLE (3125 2025);
FORCEPROP 1 LAST PART_NUMBER CS00002JB13
J 0
(3200 1925);
DISPLAY 0.489362 (3200 1925);
PAINT SKYBLUE (3200 1925);
DISPLAY INVISIBLE (3200 1925);
FORCEADD Q_RES..1
(3175 1925);
FORCEPROP 1 LAST LOCATION R1159
J 0
(2975 1925);
DISPLAY 0.489362 (2975 1925);
PAINT SKYBLUE (2975 1925);
FORCEPROP 0 LAST $SEC 1
J 0
(3375 1950);
DISPLAY 0.680851 (3375 1950);
PAINT MONO (3375 1950);
DISPLAY INVISIBLE (3375 1950);
FORCEPROP 0 LAST CDS_SEC 1
J 0
(3375 1950);
DISPLAY 0.680851 (3375 1950);
DISPLAY INVISIBLE (3375 1950);
FORCEPROP 1 LASTPIN (3075 1925) $PN 1
J 0
(3087 1937);
DISPLAY 0.787234 (3087 1937);
PAINT MONO (3087 1937);
FORCEPROP 1 LASTPIN (3275 1925) $PN 2
J 0
(3237 1937);
DISPLAY 0.787234 (3237 1937);
PAINT MONO (3237 1937);
FORCEPROP 1 LAST VALUE 0
J 2
(3375 1925);
DISPLAY 0.489362 (3375 1925);
PAINT SKYBLUE (3375 1925);
FORCEPROP 2 LAST CDS_LIB pure_quanta
J 0
(3175 1925);
DISPLAY INVISIBLE (3175 1925);
FORCEPROP 1 LAST WATTAGE 1/16W
J 2
(3575 1850);
DISPLAY 0.489362 (3575 1850);
PAINT SKYBLUE (3575 1850);
DISPLAY INVISIBLE (3575 1850);
FORCEPROP 1 LAST MATERIAL CHIP
J 0
(3600 1850);
DISPLAY 0.489362 (3600 1850);
PAINT SKYBLUE (3600 1850);
DISPLAY INVISIBLE (3600 1850);
FORCEPROP 1 LAST TOLERANCE 5%
J 0
(3150 1850);
DISPLAY 0.489362 (3150 1850);
PAINT SKYBLUE (3150 1850);
DISPLAY INVISIBLE (3150 1850);
FORCEPROP 1 LAST PACK_TYPE 0402LF
J 0
(3225 1850);
DISPLAY 0.489362 (3225 1850);
PAINT SKYBLUE (3225 1850);
DISPLAY INVISIBLE (3225 1850);
FORCEPROP 1 LAST PATH I76
J 0
(3125 2075);
DISPLAY 0.978723 (3125 2075);
PAINT WHITE (3125 2075);
DISPLAY INVISIBLE (3125 2075);
FORCEPROP 1 LAST PART_NUMBER CS00002JB13
J 0
(3200 1975);
DISPLAY 0.489362 (3200 1975);
PAINT SKYBLUE (3200 1975);
DISPLAY INVISIBLE (3200 1975);
FORCEADD OFFPAGE..3
R 2
(-825 1975);
FORCEPROP 2 LAST $XR0 160 
J 0
(-1105 1975);
DISPLAY 0.638298 (-1105 1975);
PAINT MONO (-1105 1975);
FORCEPROP 2 LAST CDS_LIB standard
J 0
(-825 1975);
DISPLAY INVISIBLE (-825 1975);
FORCEPROP 1 LAST OFFPAGE TRUE
J 2
(-1150 1850);
DISPLAY 0.872340 (-1150 1850);
PAINT GREEN (-1150 1850);
DISPLAY INVISIBLE (-1150 1850);
FORCEPROP 1 LAST COMMENT_BODY TRUE
J 2
(-775 1875);
DISPLAY 0.872340 (-775 1875);
PAINT GREEN (-775 1875);
DISPLAY INVISIBLE (-775 1875);
FORCEPROP 2 LAST PATH I77
J 0
(-775 2050);
DISPLAY 0.680851 (-775 2050);
DISPLAY INVISIBLE (-775 2050);
FORCEADD OFFPAGE..1
R 2
(2550 2075);
FORCEPROP 2 LAST $XR1 83 
J 0
(2826 2075);
DISPLAY 0.638298 (2826 2075);
PAINT MONO (2826 2075);
FORCEPROP 2 LAST $XR0 82 
J 0
(2736 2075);
DISPLAY 0.638298 (2736 2075);
PAINT MONO (2736 2075);
FORCEPROP 2 LAST CDS_LIB standard
J 2
(2550 2075);
DISPLAY INVISIBLE (2550 2075);
FORCEPROP 1 LAST OFFPAGE TRUE
J 2
(2225 1950);
DISPLAY 0.872340 (2225 1950);
PAINT GREEN (2225 1950);
DISPLAY INVISIBLE (2225 1950);
FORCEPROP 1 LAST COMMENT_BODY TRUE
J 2
(2425 1975);
DISPLAY 0.872340 (2425 1975);
PAINT GREEN (2425 1975);
DISPLAY INVISIBLE (2425 1975);
FORCEPROP 2 LAST PATH I78
J 2
(2500 2150);
DISPLAY 0.680851 (2500 2150);
DISPLAY INVISIBLE (2500 2150);
FORCEADD OFFPAGE..1
R 2
(2550 2025);
FORCEPROP 2 LAST $XR1 83 
J 0
(2826 2025);
DISPLAY 0.638298 (2826 2025);
PAINT MONO (2826 2025);
FORCEPROP 2 LAST $XR0 82 
J 0
(2736 2025);
DISPLAY 0.638298 (2736 2025);
PAINT MONO (2736 2025);
FORCEPROP 2 LAST CDS_LIB standard
J 0
(2550 2025);
DISPLAY INVISIBLE (2550 2025);
FORCEPROP 1 LAST OFFPAGE TRUE
J 2
(2225 1900);
DISPLAY 0.872340 (2225 1900);
PAINT GREEN (2225 1900);
DISPLAY INVISIBLE (2225 1900);
FORCEPROP 1 LAST COMMENT_BODY TRUE
J 2
(2425 1925);
DISPLAY 0.872340 (2425 1925);
PAINT GREEN (2425 1925);
DISPLAY INVISIBLE (2425 1925);
FORCEPROP 2 LAST PATH I79
J 0
(2725 2100);
DISPLAY 0.680851 (2725 2100);
DISPLAY INVISIBLE (2725 2100);
FORCEADD P1V0..1
(6875 3975);
FORCEPROP 3 LASTPIN (6875 3925) SIG_NAME PVDD18_S5_P0\g
J 0
(6885 3935);
DISPLAY 0.659574 (6885 3935);
PAINT MONO (6885 3935);
DISPLAY INVISIBLE (6885 3935);
FORCEPROP 1 LAST HDL_POWER PVDD18_S5_P0
J 1
(6875 4025);
DISPLAY 0.489362 (6875 4025);
PAINT GREEN (6875 4025);
FORCEPROP 2 LAST CDS_LIB pure_quanta_power
J 0
(6875 3975);
DISPLAY INVISIBLE (6875 3975);
FORCEPROP 1 LAST PATH I81
J 0
(6925 4000);
DISPLAY 0.872340 (6925 4000);
PAINT AQUA (6925 4000);
DISPLAY INVISIBLE (6925 4000);
FORCEADD P1V0..1
(6850 3050);
FORCEPROP 3 LASTPIN (6850 3000) SIG_NAME PVDD18_S5_P1\g
J 0
(6860 3010);
DISPLAY 0.659574 (6860 3010);
PAINT MONO (6860 3010);
DISPLAY INVISIBLE (6860 3010);
FORCEPROP 1 LAST HDL_POWER PVDD18_S5_P1
J 1
(6850 3100);
DISPLAY 0.489362 (6850 3100);
PAINT GREEN (6850 3100);
FORCEPROP 2 LAST CDS_LIB pure_quanta_power
J 0
(6850 3050);
DISPLAY INVISIBLE (6850 3050);
FORCEPROP 1 LAST PATH I82
J 0
(6900 3075);
DISPLAY 0.872340 (6900 3075);
PAINT AQUA (6900 3075);
DISPLAY INVISIBLE (6900 3075);
FORCEADD OFFPAGE..1
R 2
(5800 5600);
FORCEPROP 2 LAST $XR1 83 
J 0
(6076 5600);
DISPLAY 0.638298 (6076 5600);
PAINT MONO (6076 5600);
FORCEPROP 2 LAST $XR0 82 
J 0
(5986 5600);
DISPLAY 0.638298 (5986 5600);
PAINT MONO (5986 5600);
FORCEPROP 2 LAST CDS_LIB standard
J 0
(5800 5600);
DISPLAY INVISIBLE (5800 5600);
FORCEPROP 1 LAST OFFPAGE TRUE
J 2
(5475 5475);
DISPLAY 0.872340 (5475 5475);
PAINT GREEN (5475 5475);
DISPLAY INVISIBLE (5475 5475);
FORCEPROP 1 LAST COMMENT_BODY TRUE
J 2
(5675 5500);
DISPLAY 0.872340 (5675 5500);
PAINT GREEN (5675 5500);
DISPLAY INVISIBLE (5675 5500);
FORCEPROP 2 LAST PATH I84
J 0
(5975 5675);
DISPLAY 0.680851 (5975 5675);
DISPLAY INVISIBLE (5975 5675);
FORCEADD OFFPAGE..1
R 2
(5800 5550);
FORCEPROP 2 LAST $XR1 83 
J 0
(6076 5550);
DISPLAY 0.638298 (6076 5550);
PAINT MONO (6076 5550);
FORCEPROP 2 LAST $XR0 82 
J 0
(5986 5550);
DISPLAY 0.638298 (5986 5550);
PAINT MONO (5986 5550);
FORCEPROP 2 LAST CDS_LIB standard
J 0
(5800 5550);
DISPLAY INVISIBLE (5800 5550);
FORCEPROP 1 LAST OFFPAGE TRUE
J 2
(5475 5425);
DISPLAY 0.872340 (5475 5425);
PAINT GREEN (5475 5425);
DISPLAY INVISIBLE (5475 5425);
FORCEPROP 1 LAST COMMENT_BODY TRUE
J 2
(5675 5450);
DISPLAY 0.872340 (5675 5450);
PAINT GREEN (5675 5450);
DISPLAY INVISIBLE (5675 5450);
FORCEPROP 2 LAST PATH I85
J 0
(5975 5625);
DISPLAY 0.680851 (5975 5625);
DISPLAY INVISIBLE (5975 5625);
FORCEADD UNIVERSAL_GND..1
(3825 5125);
FORCEPROP 3 LASTPIN (3825 5175) SIG_NAME GND\g
J 0
(3835 5185);
DISPLAY 0.659574 (3835 5185);
PAINT MONO (3835 5185);
DISPLAY INVISIBLE (3835 5185);
FORCEPROP 2 LAST CDS_LIB pure_quanta_power
J 0
(3825 5125);
DISPLAY INVISIBLE (3825 5125);
FORCEPROP 1 LAST HDL_POWER GND
J 1
(3850 5050);
DISPLAY 0.872340 (3850 5050);
PAINT GREEN (3850 5050);
DISPLAY INVISIBLE (3850 5050);
FORCEPROP 1 LAST PATH I86
J 0
(3900 5125);
DISPLAY 0.872340 (3900 5125);
PAINT AQUA (3900 5125);
DISPLAY INVISIBLE (3900 5125);
FORCEADD P1V0..1
(4150 6200);
FORCEPROP 3 LASTPIN (4150 6150) SIG_NAME P3V3_AUX\g
J 0
(4160 6160);
DISPLAY 0.659574 (4160 6160);
PAINT MONO (4160 6160);
DISPLAY INVISIBLE (4160 6160);
FORCEPROP 1 LAST HDL_POWER P3V3_AUX
J 1
(4150 6250);
DISPLAY 0.489362 (4150 6250);
PAINT GREEN (4150 6250);
FORCEPROP 2 LAST CDS_LIB pure_quanta_power
J 0
(4150 6200);
DISPLAY INVISIBLE (4150 6200);
FORCEPROP 1 LAST PATH I87
J 0
(4200 6225);
DISPLAY 0.872340 (4200 6225);
PAINT AQUA (4200 6225);
DISPLAY INVISIBLE (4200 6225);
FORCEADD UNIVERSAL_GND..1
(3750 5700);
FORCEPROP 3 LASTPIN (3750 5750) SIG_NAME GND\g
J 0
(3760 5760);
DISPLAY 0.659574 (3760 5760);
PAINT MONO (3760 5760);
DISPLAY INVISIBLE (3760 5760);
FORCEPROP 2 LAST CDS_LIB pure_quanta_power
J 0
(3750 5700);
DISPLAY INVISIBLE (3750 5700);
FORCEPROP 1 LAST HDL_POWER GND
J 1
(3775 5625);
DISPLAY 0.872340 (3775 5625);
PAINT GREEN (3775 5625);
DISPLAY INVISIBLE (3775 5625);
FORCEPROP 1 LAST PATH I88
J 0
(3825 5700);
DISPLAY 0.872340 (3825 5700);
PAINT AQUA (3825 5700);
DISPLAY INVISIBLE (3825 5700);
FORCEADD Q_CAP..1
(3750 5900);
FORCEPROP 1 LAST LOCATION C11
J 0
(3800 6000);
DISPLAY 0.638298 (3800 6000);
FORCEPROP 0 LAST $SEC 1
J 0
(3800 6050);
DISPLAY 0.680851 (3800 6050);
PAINT MONO (3800 6050);
DISPLAY INVISIBLE (3800 6050);
FORCEPROP 0 LAST CDS_SEC 1
J 0
(3800 6050);
DISPLAY 0.680851 (3800 6050);
DISPLAY INVISIBLE (3800 6050);
FORCEPROP 1 LASTPIN (3750 6000) $PN 1
J 0
(3760 5980);
DISPLAY 0.787234 (3760 5980);
PAINT MONO (3760 5980);
FORCEPROP 1 LASTPIN (3750 5800) $PN 2
J 0
(3760 5780);
DISPLAY 0.787234 (3760 5780);
PAINT MONO (3760 5780);
FORCEPROP 1 LAST VALUE 0.1UF
J 0
(3800 5950);
DISPLAY 0.638298 (3800 5950);
FORCEPROP 1 LAST VOLTAGE 25V
J 0
(3800 5900);
DISPLAY 0.638298 (3800 5900);
FORCEPROP 1 LAST PACK_TYPE 0402
J 0
(3800 5700);
DISPLAY 0.638298 (3800 5700);
FORCEPROP 1 LAST MATERIAL X7R
J 0
(3800 5800);
DISPLAY 0.638298 (3800 5800);
FORCEPROP 1 LAST TOLERANCE 10%
J 0
(3800 5850);
DISPLAY 0.638298 (3800 5850);
FORCEPROP 2 LAST CDS_LIB pure_quanta
J 0
(3750 5900);
DISPLAY INVISIBLE (3750 5900);
FORCEPROP 1 LAST PATH I89
J 0
(3800 6050);
DISPLAY 0.978723 (3800 6050);
PAINT WHITE (3800 6050);
DISPLAY INVISIBLE (3800 6050);
FORCEPROP 1 LAST PART_NUMBER CH4104K1B00
J 0
(3800 5750);
DISPLAY 0.638298 (3800 5750);
DISPLAY INVISIBLE (3800 5750);
FORCEADD Q_RES..1
(5825 5450);
FORCEPROP 1 LAST LOCATION R327
J 0
(5600 5450);
DISPLAY 0.638298 (5600 5450);
FORCEPROP 0 LAST $SEC 1
J 0
(6250 5500);
DISPLAY 0.680851 (6250 5500);
PAINT MONO (6250 5500);
DISPLAY INVISIBLE (6250 5500);
FORCEPROP 0 LAST CDS_SEC 1
J 0
(6250 5500);
DISPLAY 0.680851 (6250 5500);
DISPLAY INVISIBLE (6250 5500);
FORCEPROP 1 LASTPIN (5725 5450) $PN 1
J 0
(5737 5462);
DISPLAY 0.787234 (5737 5462);
PAINT MONO (5737 5462);
FORCEPROP 1 LASTPIN (5925 5450) $PN 2
J 0
(5887 5462);
DISPLAY 0.787234 (5887 5462);
PAINT MONO (5887 5462);
FORCEPROP 1 LAST MATERIAL CHIP
J 0
(6075 5450);
DISPLAY 0.638298 (6075 5450);
FORCEPROP 1 LAST VALUE 0
J 2
(6025 5450);
DISPLAY 0.638298 (6025 5450);
FORCEPROP 1 LAST PACK_TYPE 0402LF
J 0
(6250 5450);
DISPLAY 0.638298 (6250 5450);
FORCEPROP 2 LAST CDS_LIB pure_quanta
J 0
(5825 5450);
DISPLAY INVISIBLE (5825 5450);
FORCEPROP 1 LAST TOLERANCE 5%
J 0
(5800 5350);
DISPLAY 0.978723 (5800 5350);
DISPLAY INVISIBLE (5800 5350);
FORCEPROP 1 LAST WATTAGE 1/16W
J 2
(5800 5300);
DISPLAY 0.978723 (5800 5300);
DISPLAY INVISIBLE (5800 5300);
FORCEPROP 1 LAST PATH I91
J 0
(5775 5600);
DISPLAY 0.978723 (5775 5600);
PAINT WHITE (5775 5600);
DISPLAY INVISIBLE (5775 5600);
FORCEPROP 1 LAST PART_NUMBER CS00002JB13
J 0
(5950 5475);
DISPLAY 0.978723 (5950 5475);
DISPLAY INVISIBLE (5950 5475);
FORCEADD Q_RES..1
(5825 5400);
FORCEPROP 1 LAST LOCATION R328
J 0
(5600 5400);
DISPLAY 0.638298 (5600 5400);
FORCEPROP 0 LAST $SEC 1
J 0
(6250 5450);
DISPLAY 0.680851 (6250 5450);
PAINT MONO (6250 5450);
DISPLAY INVISIBLE (6250 5450);
FORCEPROP 0 LAST CDS_SEC 1
J 0
(6250 5450);
DISPLAY 0.680851 (6250 5450);
DISPLAY INVISIBLE (6250 5450);
FORCEPROP 1 LASTPIN (5725 5400) $PN 1
J 0
(5737 5412);
DISPLAY 0.787234 (5737 5412);
PAINT MONO (5737 5412);
FORCEPROP 1 LASTPIN (5925 5400) $PN 2
J 0
(5887 5412);
DISPLAY 0.787234 (5887 5412);
PAINT MONO (5887 5412);
FORCEPROP 1 LAST MATERIAL CHIP
J 0
(6075 5400);
DISPLAY 0.638298 (6075 5400);
FORCEPROP 1 LAST PACK_TYPE 0402LF
J 0
(6250 5400);
DISPLAY 0.638298 (6250 5400);
FORCEPROP 1 LAST VALUE 0
J 2
(6025 5400);
DISPLAY 0.638298 (6025 5400);
FORCEPROP 1 LAST TOLERANCE 5%
J 0
(5800 5300);
DISPLAY 0.978723 (5800 5300);
DISPLAY INVISIBLE (5800 5300);
FORCEPROP 1 LAST WATTAGE 1/16W
J 2
(5800 5250);
DISPLAY 0.978723 (5800 5250);
DISPLAY INVISIBLE (5800 5250);
FORCEPROP 2 LAST CDS_LIB pure_quanta
J 0
(5825 5400);
DISPLAY INVISIBLE (5825 5400);
FORCEPROP 1 LAST PATH I92
J 0
(5775 5550);
DISPLAY 0.978723 (5775 5550);
PAINT WHITE (5775 5550);
DISPLAY INVISIBLE (5775 5550);
FORCEPROP 1 LAST PART_NUMBER CS00002JB13
J 0
(5950 5425);
DISPLAY 0.978723 (5950 5425);
DISPLAY INVISIBLE (5950 5425);
FORCEADD Q_RES..1
(5825 5350);
FORCEPROP 1 LAST LOCATION R337
J 0
(5600 5350);
DISPLAY 0.638298 (5600 5350);
FORCEPROP 0 LAST $SEC 1
J 0
(6250 5400);
DISPLAY 0.680851 (6250 5400);
PAINT MONO (6250 5400);
DISPLAY INVISIBLE (6250 5400);
FORCEPROP 0 LAST CDS_SEC 1
J 0
(6250 5400);
DISPLAY 0.680851 (6250 5400);
DISPLAY INVISIBLE (6250 5400);
FORCEPROP 1 LASTPIN (5725 5350) $PN 1
J 0
(5737 5362);
DISPLAY 0.787234 (5737 5362);
PAINT MONO (5737 5362);
FORCEPROP 1 LASTPIN (5925 5350) $PN 2
J 0
(5887 5362);
DISPLAY 0.787234 (5887 5362);
PAINT MONO (5887 5362);
FORCEPROP 1 LAST MATERIAL CHIP
J 0
(6075 5350);
DISPLAY 0.638298 (6075 5350);
FORCEPROP 1 LAST PACK_TYPE 0402LF
J 0
(6250 5350);
DISPLAY 0.638298 (6250 5350);
FORCEPROP 1 LAST VALUE 0
J 2
(6025 5350);
DISPLAY 0.638298 (6025 5350);
FORCEPROP 1 LAST WATTAGE 1/16W
J 2
(5800 5200);
DISPLAY 0.978723 (5800 5200);
DISPLAY INVISIBLE (5800 5200);
FORCEPROP 1 LAST TOLERANCE 5%
J 0
(5800 5250);
DISPLAY 0.978723 (5800 5250);
DISPLAY INVISIBLE (5800 5250);
FORCEPROP 2 LAST CDS_LIB pure_quanta
J 0
(5825 5350);
DISPLAY INVISIBLE (5825 5350);
FORCEPROP 1 LAST PATH I93
J 0
(5775 5500);
DISPLAY 0.978723 (5775 5500);
PAINT WHITE (5775 5500);
DISPLAY INVISIBLE (5775 5500);
FORCEPROP 1 LAST PART_NUMBER CS00002JB13
J 0
(5950 5375);
DISPLAY 0.978723 (5950 5375);
DISPLAY INVISIBLE (5950 5375);
FORCEADD Q_RES..1
(5825 5300);
FORCEPROP 1 LAST LOCATION R338
J 0
(5600 5300);
DISPLAY 0.638298 (5600 5300);
FORCEPROP 0 LAST $SEC 1
J 0
(6250 5350);
DISPLAY 0.680851 (6250 5350);
PAINT MONO (6250 5350);
DISPLAY INVISIBLE (6250 5350);
FORCEPROP 0 LAST CDS_SEC 1
J 0
(6250 5350);
DISPLAY 0.680851 (6250 5350);
DISPLAY INVISIBLE (6250 5350);
FORCEPROP 1 LASTPIN (5725 5300) $PN 1
J 0
(5737 5312);
DISPLAY 0.787234 (5737 5312);
PAINT MONO (5737 5312);
FORCEPROP 1 LASTPIN (5925 5300) $PN 2
J 0
(5887 5312);
DISPLAY 0.787234 (5887 5312);
PAINT MONO (5887 5312);
FORCEPROP 1 LAST MATERIAL CHIP
J 0
(6075 5300);
DISPLAY 0.638298 (6075 5300);
FORCEPROP 1 LAST VALUE 0
J 2
(6025 5300);
DISPLAY 0.638298 (6025 5300);
FORCEPROP 1 LAST PACK_TYPE 0402LF
J 0
(6250 5300);
DISPLAY 0.638298 (6250 5300);
FORCEPROP 2 LAST CDS_LIB pure_quanta
J 0
(5825 5300);
DISPLAY INVISIBLE (5825 5300);
FORCEPROP 1 LAST WATTAGE 1/16W
J 2
(5800 5150);
DISPLAY 0.978723 (5800 5150);
DISPLAY INVISIBLE (5800 5150);
FORCEPROP 1 LAST TOLERANCE 5%
J 0
(5800 5200);
DISPLAY 0.978723 (5800 5200);
DISPLAY INVISIBLE (5800 5200);
FORCEPROP 1 LAST PATH I94
J 0
(5775 5450);
DISPLAY 0.978723 (5775 5450);
PAINT WHITE (5775 5450);
DISPLAY INVISIBLE (5775 5450);
FORCEPROP 1 LAST PART_NUMBER CS00002JB13
J 0
(5950 5325);
DISPLAY 0.978723 (5950 5325);
DISPLAY INVISIBLE (5950 5325);
FORCEADD OFFPAGE..2
(7275 5450);
FORCEPROP 2 LAST $XR1 27 
J 0
(7584 5450);
DISPLAY 0.638298 (7584 5450);
PAINT MONO (7584 5450);
FORCEPROP 2 LAST $XR0 161 
J 0
(7464 5450);
DISPLAY 0.638298 (7464 5450);
PAINT MONO (7464 5450);
FORCEPROP 2 LAST CDS_LIB standard
J 0
(7275 5450);
DISPLAY INVISIBLE (7275 5450);
FORCEPROP 1 LAST OFFPAGE TRUE
J 0
(7600 5325);
DISPLAY 0.872340 (7600 5325);
PAINT GREEN (7600 5325);
DISPLAY INVISIBLE (7600 5325);
FORCEPROP 1 LAST COMMENT_BODY TRUE
J 0
(7230 5355);
DISPLAY 0.872340 (7230 5355);
PAINT GREEN (7230 5355);
DISPLAY INVISIBLE (7230 5355);
FORCEPROP 2 LAST PATH I95
J 0
(7450 5525);
DISPLAY 0.680851 (7450 5525);
DISPLAY INVISIBLE (7450 5525);
FORCEADD OFFPAGE..2
(7275 5350);
FORCEPROP 2 LAST $XR1 54 
J 0
(7584 5350);
DISPLAY 0.638298 (7584 5350);
PAINT MONO (7584 5350);
FORCEPROP 2 LAST $XR0 161 
J 0
(7464 5350);
DISPLAY 0.638298 (7464 5350);
PAINT MONO (7464 5350);
FORCEPROP 2 LAST CDS_LIB standard
J 0
(7275 5350);
DISPLAY INVISIBLE (7275 5350);
FORCEPROP 1 LAST OFFPAGE TRUE
J 0
(7600 5225);
DISPLAY 0.872340 (7600 5225);
PAINT GREEN (7600 5225);
DISPLAY INVISIBLE (7600 5225);
FORCEPROP 1 LAST COMMENT_BODY TRUE
J 0
(7230 5255);
DISPLAY 0.872340 (7230 5255);
PAINT GREEN (7230 5255);
DISPLAY INVISIBLE (7230 5255);
FORCEPROP 2 LAST PATH I96
J 0
(7450 5425);
DISPLAY 0.680851 (7450 5425);
DISPLAY INVISIBLE (7450 5425);
FORCEADD OFFPAGE..3
(7250 5400);
FORCEPROP 2 LAST $XR1 27 
J 0
(7584 5400);
DISPLAY 0.638298 (7584 5400);
PAINT MONO (7584 5400);
FORCEPROP 2 LAST $XR0 161 
J 0
(7464 5400);
DISPLAY 0.638298 (7464 5400);
PAINT MONO (7464 5400);
FORCEPROP 2 LAST CDS_LIB standard
J 0
(7250 5400);
DISPLAY INVISIBLE (7250 5400);
FORCEPROP 1 LAST OFFPAGE TRUE
J 0
(7575 5275);
DISPLAY 0.872340 (7575 5275);
PAINT GREEN (7575 5275);
DISPLAY INVISIBLE (7575 5275);
FORCEPROP 1 LAST COMMENT_BODY TRUE
J 0
(7200 5300);
DISPLAY 0.872340 (7200 5300);
PAINT PEACH (7200 5300);
DISPLAY INVISIBLE (7200 5300);
FORCEPROP 2 LAST PATH I97
J 0
(7450 5475);
DISPLAY 0.680851 (7450 5475);
DISPLAY INVISIBLE (7450 5475);
FORCEADD OFFPAGE..3
(7275 5300);
FORCEPROP 2 LAST $XR1 54 
J 0
(7609 5300);
DISPLAY 0.638298 (7609 5300);
PAINT MONO (7609 5300);
FORCEPROP 2 LAST $XR0 161 
J 0
(7489 5300);
DISPLAY 0.638298 (7489 5300);
PAINT MONO (7489 5300);
FORCEPROP 2 LAST CDS_LIB standard
J 0
(7275 5300);
DISPLAY INVISIBLE (7275 5300);
FORCEPROP 1 LAST OFFPAGE TRUE
J 0
(7600 5175);
DISPLAY 0.872340 (7600 5175);
PAINT GREEN (7600 5175);
DISPLAY INVISIBLE (7600 5175);
FORCEPROP 1 LAST COMMENT_BODY TRUE
J 0
(7225 5200);
DISPLAY 0.872340 (7225 5200);
PAINT PEACH (7225 5200);
DISPLAY INVISIBLE (7225 5200);
FORCEPROP 2 LAST PATH I98
J 0
(7475 5375);
DISPLAY 0.680851 (7475 5375);
DISPLAY INVISIBLE (7475 5375);
FORCEADD Q_RES..1
(3025 5550);
FORCEPROP 1 LAST LOCATION R325
J 0
(2800 5550);
DISPLAY 0.808511 (2800 5550);
FORCEPROP 0 LAST $SEC 1
J 0
(2850 5600);
DISPLAY 0.680851 (2850 5600);
PAINT MONO (2850 5600);
DISPLAY INVISIBLE (2850 5600);
FORCEPROP 0 LAST CDS_SEC 1
J 0
(2850 5600);
DISPLAY 0.680851 (2850 5600);
DISPLAY INVISIBLE (2850 5600);
FORCEPROP 1 LASTPIN (2925 5550) $PN 1
J 0
(2937 5562);
DISPLAY 0.787234 (2937 5562);
PAINT MONO (2937 5562);
FORCEPROP 1 LASTPIN (3125 5550) $PN 2
J 0
(3087 5562);
DISPLAY 0.787234 (3087 5562);
PAINT MONO (3087 5562);
FORCEPROP 1 LAST PACK_TYPE 0402LF
J 0
(3375 5550);
DISPLAY 0.510638 (3375 5550);
FORCEPROP 1 LAST VALUE 0
J 2
(3200 5550);
DISPLAY 0.510638 (3200 5550);
FORCEPROP 1 LAST MATERIAL CHIP
J 0
(3225 5550);
DISPLAY 0.510638 (3225 5550);
FORCEPROP 1 LAST WATTAGE 1/16W
J 2
(3000 5400);
DISPLAY 0.978723 (3000 5400);
DISPLAY INVISIBLE (3000 5400);
FORCEPROP 1 LAST TOLERANCE 5%
J 0
(3000 5450);
DISPLAY 0.978723 (3000 5450);
DISPLAY INVISIBLE (3000 5450);
FORCEPROP 2 LAST CDS_LIB pure_quanta
J 0
(3025 5550);
DISPLAY INVISIBLE (3025 5550);
FORCEPROP 1 LAST PATH I99
J 0
(2975 5700);
DISPLAY 0.978723 (2975 5700);
PAINT WHITE (2975 5700);
DISPLAY INVISIBLE (2975 5700);
FORCEPROP 1 LAST PART_NUMBER CS00002JB13
J 0
(3150 5575);
DISPLAY 0.978723 (3150 5575);
DISPLAY INVISIBLE (3150 5575);
FORCEADD DNS..1
(1625 4225);
PAINT RED (1625 4225);
FORCEPROP 2 LAST CDS_LIB mstr_misc
J 0
(1625 4225);
DISPLAY INVISIBLE (1625 4225);
FORCEPROP 1 LAST COMMENT_BODY TRUE
R 1
J 0
(1700 4000);
DISPLAY 0.872340 (1700 4000);
PAINT GREEN (1700 4000);
DISPLAY INVISIBLE (1700 4000);
FORCEADD DNS..1
(1775 3200);
PAINT RED (1775 3200);
FORCEPROP 2 LAST CDS_LIB mstr_misc
J 0
(1775 3200);
DISPLAY INVISIBLE (1775 3200);
FORCEPROP 1 LAST COMMENT_BODY TRUE
R 1
J 0
(1850 2975);
DISPLAY 0.872340 (1850 2975);
PAINT GREEN (1850 2975);
DISPLAY INVISIBLE (1850 2975);
FORCEADD CAD_NOTE..1
(4750 4750);
FORCEPROP 0 LAST L1 R327/R1156 R328/R1155 CO-LAY
J 0
(4600 4625);
DISPLAY 1.489362 (4600 4625);
PAINT WHITE (4600 4625);
FORCEPROP 2 LAST CDS_LIB pure_quanta_power
J 0
(4750 4750);
DISPLAY INVISIBLE (4750 4750);
FORCEPROP 1 LAST COMMENT_BODY TRUE
J 0
(4775 4850);
DISPLAY 0.574468 (4775 4850);
PAINT WHITE (4775 4850);
DISPLAY INVISIBLE (4775 4850);
FORCEADD CAD_NOTE..1
(4775 4525);
FORCEPROP 0 LAST L1 R337/R1157 R338/R1158 CO-LAY
J 0
(4625 4400);
DISPLAY 1.489362 (4625 4400);
PAINT WHITE (4625 4400);
FORCEPROP 2 LAST CDS_LIB pure_quanta_power
J 0
(4775 4525);
DISPLAY INVISIBLE (4775 4525);
FORCEPROP 1 LAST COMMENT_BODY TRUE
J 0
(4800 4625);
DISPLAY 0.574468 (4800 4625);
PAINT WHITE (4800 4625);
DISPLAY INVISIBLE (4800 4625);
FORCEADD DNS..1
(1675 2850);
PAINT RED (1675 2850);
FORCEPROP 2 LAST CDS_LIB mstr_misc
J 0
(1675 2850);
DISPLAY INVISIBLE (1675 2850);
FORCEPROP 1 LAST COMMENT_BODY TRUE
R 1
J 0
(1750 2625);
DISPLAY 0.872340 (1750 2625);
PAINT GREEN (1750 2625);
DISPLAY INVISIBLE (1750 2625);
FORCEADD DNS..1
(1750 1075);
PAINT RED (1750 1075);
FORCEPROP 2 LAST CDS_LIB mstr_misc
J 0
(1750 1075);
DISPLAY INVISIBLE (1750 1075);
FORCEPROP 1 LAST COMMENT_BODY TRUE
R 1
J 0
(1825 850);
DISPLAY 0.872340 (1825 850);
PAINT GREEN (1825 850);
DISPLAY INVISIBLE (1825 850);
FORCEADD QUANTA_TITLE_BLOCK_C..1
(7700 -175);
FORCEPROP 0 LAST CDS_CON_LAST_MODIFIED Thu Sep 14 16:12:15 2023
J 0
(5815 -160);
DISPLAY INVISIBLE (5815 -160);
FORCEPROP 1 LAST CUSTOM_TXT_CDS <CON_LAST_MODIFIED>
J 0
(5815 -160);
DISPLAY 0.978723 (5815 -160);
FORCEPROP 2 LAST CUSTOM_TXT_CDS <XR_PAGE_TITLE>
J 0
(-190 5075);
DISPLAY 0.638298 (-190 5075);
PAINT PINK (-190 5075);
DISPLAY INVISIBLE (-190 5075);
FORCEPROP 1 LAST CUSTOM_TXT_CDS <NAME_2>
J 0
(4525 -125);
FORCEPROP 1 LAST CUSTOM_TXT_CDS <NAME_1>
J 0
(4525 0);
FORCEPROP 1 LAST CUSTOM_TXT_CDS <Q_NUMBER>
J 0
(6297 -72);
DISPLAY 1.212766 (6297 -72);
FORCEPROP 1 LAST CUSTOM_TXT_CDS <Q_PROJ>
J 0
(5318 -73);
DISPLAY 1.212766 (5318 -73);
FORCEPROP 1 LAST CUSTOM_TXT_CDS <Q_REV>
J 0
(7516 -72);
DISPLAY 1.212766 (7516 -72);
FORCEPROP 1 LAST CUSTOM_TXT_CDS <CON_PAGE_NUM> OF <CON_TOTAL_PAGES>
J 0
(7254 -157);
DISPLAY 0.978723 (7254 -157);
FORCEPROP 1 LAST Q_TITLE I2C MUX - APML(2/2)
J 0
(-1600 -100);
DISPLAY 2.446809 (-1600 -100);
PAINT GREEN (-1600 -100);
FORCEPROP 2 LAST PAGE_BORDER TRUE
J 0
(-190 5075);
DISPLAY 0.638298 (-190 5075);
PAINT PINK (-190 5075);
DISPLAY INVISIBLE (-190 5075);
FORCEPROP 1 LAST CDS_LMAN_SYM_OUTLINE -9475,6775,100,-125
J 0
(7700 -175);
DISPLAY 0.468085 (7700 -175);
PAINT GREEN (7700 -175);
DISPLAY INVISIBLE (7700 -175);
FORCEPROP 2 LAST CDS_LIB pure_quanta
J 0
(7700 -175);
DISPLAY INVISIBLE (7700 -175);
FORCEPROP 2 LAST CDS_XR_PAGE_TITLE CR-161 : @T6G_MB_LIB.T6G(SCH_1):PAGE161
J 0
(-190 5075);
DISPLAY 0.638298 (-190 5075);
PAINT PINK (-190 5075);
DISPLAY INVISIBLE (-190 5075);
FORCEPROP 1 LAST Q_DEPT BU9
J 1
(3937 -126);
DISPLAY 1.957447 (3937 -126);
PAINT GREEN (3937 -126);
DISPLAY INVISIBLE (3937 -126);
FORCEPROP 1 LAST COMMENT_BODY TRUE
J 0
(7712 -188);
DISPLAY 0.978723 (7712 -188);
PAINT GREEN (7712 -188);
DISPLAY INVISIBLE (7712 -188);
FORCEADD CAD_NOTE..1
(-675 5650);
FORCEPROP 0 LAST L1 R323/R326 R324/R325 CO-LAY
J 0
(-825 5525);
DISPLAY 1.489362 (-825 5525);
PAINT WHITE (-825 5525);
FORCEPROP 2 LAST CDS_LIB pure_quanta_power
J 0
(-675 5650);
DISPLAY INVISIBLE (-675 5650);
FORCEPROP 1 LAST COMMENT_BODY TRUE
J 0
(-650 5750);
DISPLAY 0.574468 (-650 5750);
PAINT WHITE (-650 5750);
DISPLAY INVISIBLE (-650 5750);
FORCEADD DNS..1
(1725 4975);
PAINT RED (1725 4975);
FORCEPROP 2 LAST CDS_LIB mstr_misc
J 0
(1725 4975);
DISPLAY INVISIBLE (1725 4975);
FORCEPROP 1 LAST COMMENT_BODY TRUE
R 1
J 0
(1800 4750);
DISPLAY 0.872340 (1800 4750);
PAINT GREEN (1800 4750);
DISPLAY INVISIBLE (1800 4750);
FORCEADD DNS..1
(3125 4025);
PAINT RED (3125 4025);
FORCEPROP 2 LAST CDS_LIB mstr_misc
J 0
(3125 4025);
DISPLAY INVISIBLE (3125 4025);
FORCEPROP 1 LAST COMMENT_BODY TRUE
R 1
J 0
(3200 3800);
DISPLAY 0.872340 (3200 3800);
PAINT GREEN (3200 3800);
DISPLAY INVISIBLE (3200 3800);
FORCEADD DNS..1
(3125 3875);
PAINT RED (3125 3875);
FORCEPROP 2 LAST CDS_LIB mstr_misc
J 0
(3125 3875);
DISPLAY INVISIBLE (3125 3875);
FORCEPROP 1 LAST COMMENT_BODY TRUE
R 1
J 0
(3200 3650);
DISPLAY 0.872340 (3200 3650);
PAINT GREEN (3200 3650);
DISPLAY INVISIBLE (3200 3650);
FORCEADD DNS..1
(650 4325);
PAINT RED (650 4325);
FORCEPROP 2 LAST CDS_LIB mstr_misc
J 0
(650 4325);
DISPLAY INVISIBLE (650 4325);
FORCEPROP 1 LAST COMMENT_BODY TRUE
R 1
J 0
(725 4100);
DISPLAY 0.872340 (725 4100);
PAINT GREEN (725 4100);
DISPLAY INVISIBLE (725 4100);
FORCEADD DNS..1
(375 4500);
PAINT RED (375 4500);
FORCEPROP 2 LAST CDS_LIB mstr_misc
J 0
(375 4500);
DISPLAY INVISIBLE (375 4500);
FORCEPROP 1 LAST COMMENT_BODY TRUE
R 1
J 0
(450 4275);
DISPLAY 0.872340 (450 4275);
PAINT GREEN (450 4275);
DISPLAY INVISIBLE (450 4275);
FORCEADD DNS..1
(150 4350);
PAINT RED (150 4350);
FORCEPROP 2 LAST CDS_LIB mstr_misc
J 0
(150 4350);
DISPLAY INVISIBLE (150 4350);
FORCEPROP 1 LAST COMMENT_BODY TRUE
R 1
J 0
(225 4125);
DISPLAY 0.872340 (225 4125);
PAINT GREEN (225 4125);
DISPLAY INVISIBLE (225 4125);
FORCEADD DNS..1
(-550 3875);
PAINT RED (-550 3875);
FORCEPROP 2 LAST CDS_LIB mstr_misc
J 0
(-550 3875);
DISPLAY INVISIBLE (-550 3875);
FORCEPROP 1 LAST COMMENT_BODY TRUE
R 1
J 0
(-475 3650);
DISPLAY 0.872340 (-475 3650);
PAINT GREEN (-475 3650);
DISPLAY INVISIBLE (-475 3650);
WIRE 16 -1 (1325 1775)(1225 1775);
WIRE 16 -1 (1225 1775)(1225 1650);
WIRE 16 -1 (2100 3775)(2125 3775);
WIRE 16 -1 (2125 3775)(2125 3625);
WIRE 16 -1 (2800 3500)(2800 3400);
WIRE 16 -1 (175 4250)(175 4200);
WIRE 16 -1 (700 4250)(700 4200);
WIRE 16 -1 (750 2250)(750 2200);
WIRE 16 -1 (4300 5300)(3825 5300);
WIRE 16 -1 (3825 5300)(3825 5175);
WIRE 16 -1 (3750 5800)(3750 5750);
WIRE 16 -1 (4900 5400)(5725 5400);
FORCEPROP 2 LAST SIG_NAME SMB_APML_CPU0_MUX2_SDA
J 0
(4965 5400);
DISPLAY 0.489362 (4965 5400);
FORCEPROP 2 LASTPROP $XRERR UNIQUE?
J 0
(4725 5400);
DISPLAY 0.638298 (4725 5400);
PAINT MONO (4725 5400);
DISPLAY INVISIBLE (4725 5400);
WIRE 16 -1 (4900 5600)(5750 5600);
FORCEPROP 2 LAST SIG_NAME FM_APML_MUX2_OE_N
J 0
(5065 5610);
DISPLAY 0.680851 (5065 5610);
WIRE 16 -1 (4900 5550)(5750 5550);
FORCEPROP 2 LAST SIG_NAME FM_APML_MUX2_SEL
J 0
(5065 5560);
DISPLAY 0.680851 (5065 5560);
WIRE 16 -1 (4300 5500)(3125 5500);
FORCEPROP 2 LAST SIG_NAME SMB_CPU0_CPU1_APML_MUX2_SDA
J 0
(3590 5500);
DISPLAY 0.510638 (3590 5500);
PAINT WHITE (3590 5500);
FORCEPROP 2 LASTPROP $XRERR UNIQUE?
J 0
(3350 5500);
DISPLAY 0.638298 (3350 5500);
PAINT MONO (3350 5500);
DISPLAY INVISIBLE (3350 5500);
WIRE 16 -1 (4300 5550)(3125 5550);
FORCEPROP 2 LAST SIG_NAME SMB_CPU0_CPU1_APML_MUX2_SCL
J 0
(3590 5550);
DISPLAY 0.510638 (3590 5550);
PAINT WHITE (3590 5550);
FORCEPROP 2 LASTPROP $XRERR UNIQUE?
J 0
(3350 5550);
DISPLAY 0.638298 (3350 5550);
PAINT MONO (3350 5550);
DISPLAY INVISIBLE (3350 5550);
WIRE 16 -1 (2925 5500)(2225 5500);
FORCEPROP 2 LAST SIG_NAME SMB_CPU0_CPU1_APML_SDA_R2
J 0
(2215 5510);
DISPLAY 0.404255 (2215 5510);
PAINT WHITE (2215 5510);
WIRE 16 -1 (1250 4075)(250 4075);
FORCEPROP 2 LAST SIG_NAME I3C_MUX_CPU0_VIO
J 0
(290 4085);
DISPLAY 0.489362 (290 4085);
FORCEPROP 2 LASTPROP $XRERR UNIQUE?
J 0
(50 4085);
DISPLAY 0.638298 (50 4085);
PAINT MONO (50 4085);
DISPLAY INVISIBLE (50 4085);
WIRE 16 -1 (250 4525)(250 4075);
WIRE 16 -1 (250 4525)(325 4525);
WIRE 16 -1 (175 4525)(250 4525);
WIRE 16 -1 (175 4450)(175 4525);
WIRE 16 -1 (725 3150)(1600 3150);
WIRE 16 -1 (725 3875)(725 3150);
WIRE 16 -1 (725 3875)(1250 3875);
WIRE 16 -1 (-75 3875)(725 3875);
FORCEPROP 2 LAST SIG_NAME SMB_CPU0_CPU1_APML_MUX1_SDA
J 0
(-35 3885);
DISPLAY 0.510638 (-35 3885);
PAINT WHITE (-35 3885);
FORCEPROP 2 LASTPROP $XRERR UNIQUE?
J 0
(-275 3885);
DISPLAY 0.638298 (-275 3885);
PAINT MONO (-275 3885);
DISPLAY INVISIBLE (-275 3885);
WIRE 16 -1 (-75 3875)(-75 4925);
WIRE 16 -1 (-475 3875)(-75 3875);
WIRE 16 -1 (-75 4925)(1550 4925);
WIRE 16 -1 (1550 5000)(-150 5000);
WIRE 16 -1 (-150 5000)(-150 3825);
WIRE 16 -1 (-150 3825)(775 3825);
FORCEPROP 2 LAST SIG_NAME SMB_CPU0_CPU1_APML_MUX1_SCL
J 0
(-10 3835);
DISPLAY 0.510638 (-10 3835);
PAINT WHITE (-10 3835);
FORCEPROP 2 LASTPROP $XRERR UNIQUE?
J 0
(-250 3835);
DISPLAY 0.638298 (-250 3835);
PAINT MONO (-250 3835);
DISPLAY INVISIBLE (-250 3835);
WIRE 16 -1 (-475 3825)(-150 3825);
WIRE 16 -1 (775 3825)(1250 3825);
WIRE 16 -1 (775 3825)(775 3225);
WIRE 16 -1 (775 3225)(1600 3225);
WIRE 16 -1 (-675 3875)(-1175 3875);
FORCEPROP 2 LAST SIG_NAME SMB_CPU0_CPU1_APML_SDA_R2
J 0
(-1210 3885);
DISPLAY 0.404255 (-1210 3885);
PAINT WHITE (-1210 3885);
WIRE 16 -1 (2725 3975)(2725 5000);
WIRE 16 -1 (3050 3975)(2725 3975);
WIRE 16 -1 (2725 3975)(2100 3975);
FORCEPROP 2 LAST SIG_NAME SMB_APML_CPU0_R_SCL
J 2
(2615 3985);
DISPLAY 0.489362 (2615 3985);
FORCEPROP 2 LASTPROP $XRERR UNIQUE?
J 0
(2375 3985);
DISPLAY 0.638298 (2375 3985);
PAINT MONO (2375 3985);
DISPLAY INVISIBLE (2375 3985);
WIRE 16 -1 (1750 5000)(2725 5000);
WIRE 16 -1 (-675 3825)(-1175 3825);
FORCEPROP 2 LAST SIG_NAME SMB_CPU0_CPU1_APML_SCL_R2
J 0
(-1210 3835);
DISPLAY 0.404255 (-1210 3835);
PAINT WHITE (-1210 3835);
WIRE 16 -1 (1925 1875)(2950 1875);
FORCEPROP 2 LAST SIG_NAME SMB_CPU0_SEC_R_SDA
J 2
(2865 1885);
DISPLAY 0.489362 (2865 1885);
FORCEPROP 2 LASTPROP $XRERR UNIQUE?
J 0
(2625 1885);
DISPLAY 0.638298 (2625 1885);
PAINT MONO (2625 1885);
DISPLAY INVISIBLE (2625 1885);
WIRE 16 -1 (2950 1875)(2950 2875);
WIRE 16 -1 (2950 1875)(3075 1875);
WIRE 16 -1 (1750 2875)(2950 2875);
WIRE 16 -1 (1925 1925)(2900 1925);
FORCEPROP 2 LAST SIG_NAME SMB_CPU0_SEC_R_SCL
J 2
(2865 1935);
DISPLAY 0.489362 (2865 1935);
FORCEPROP 2 LASTPROP $XRERR UNIQUE?
J 0
(2625 1935);
DISPLAY 0.638298 (2625 1935);
PAINT MONO (2625 1935);
DISPLAY INVISIBLE (2625 1935);
WIRE 16 -1 (2900 2800)(2900 1925);
WIRE 16 -1 (2900 1925)(3075 1925);
WIRE 16 -1 (1750 2800)(2900 2800);
WIRE 16 -1 (-75 2800)(1550 2800);
WIRE 16 -1 (-75 2025)(-75 2800);
WIRE 16 -1 (-75 2025)(-25 2025);
WIRE 16 -1 (-775 2025)(-75 2025);
FORCEPROP 2 LAST SIG_NAME SMB_CPU0_CPU1_SEC_SCL_R2
J 0
(-785 2035);
DISPLAY 0.510638 (-785 2035);
PAINT WHITE (-785 2035);
WIRE 16 -1 (-25 2025)(1325 2025);
WIRE 16 -1 (-25 2025)(-25 1025);
WIRE 16 -1 (-25 1025)(1625 1025);
WIRE 16 -1 (1550 2875)(-150 2875);
WIRE 16 -1 (-150 2875)(-150 1975);
WIRE 16 -1 (-150 1975)(25 1975);
WIRE 16 -1 (-775 1975)(-150 1975);
FORCEPROP 2 LAST SIG_NAME SMB_CPU0_CPU1_SEC_SDA_R2
J 0
(-785 1985);
DISPLAY 0.510638 (-785 1985);
PAINT WHITE (-785 1985);
WIRE 16 -1 (25 1975)(1325 1975);
WIRE 16 -1 (25 1975)(25 1100);
WIRE 16 -1 (25 1100)(1625 1100);
WIRE 16 -1 (5050 2475)(5900 2475);
FORCEPROP 2 LAST SIG_NAME SMB_APML_CPU1_SDA
J 2
(5590 2485);
DISPLAY 0.489362 (5590 2485);
WIRE 16 -1 (5900 2625)(5900 2475);
WIRE 16 -1 (5050 2425)(6225 2425);
FORCEPROP 2 LAST SIG_NAME SMB_APML_CPU1_SCL
J 2
(5590 2435);
DISPLAY 0.489362 (5590 2435);
WIRE 16 -1 (6225 2625)(6225 2425);
WIRE 16 -1 (5175 3425)(5925 3425);
FORCEPROP 2 LAST SIG_NAME SMB_APML_CPU0_SDA
J 2
(5690 3435);
DISPLAY 0.489362 (5690 3435);
WIRE 16 -1 (5925 3550)(5925 3425);
WIRE 16 -1 (5175 3375)(6250 3375);
FORCEPROP 2 LAST SIG_NAME SMB_APML_CPU0_SCL
J 2
(5690 3385);
DISPLAY 0.489362 (5690 3385);
WIRE 16 -1 (6250 3550)(6250 3375);
WIRE 16 -1 (3275 1825)(4000 1825);
FORCEPROP 2 LAST SIG_NAME SMB_CPU1_SEC_SCL
J 2
(3825 1835);
DISPLAY 0.489362 (3825 1835);
WIRE 16 -1 (3275 1775)(4000 1775);
FORCEPROP 2 LAST SIG_NAME SMB_CPU1_SEC_SDA
J 2
(3825 1785);
DISPLAY 0.489362 (3825 1785);
WIRE 16 -1 (1925 1825)(2750 1825);
FORCEPROP 2 LAST SIG_NAME SMB_CPU1_SEC_R_SCL
J 2
(2640 1835);
DISPLAY 0.489362 (2640 1835);
FORCEPROP 2 LASTPROP $XRERR UNIQUE?
J 0
(2400 1835);
DISPLAY 0.638298 (2400 1835);
PAINT MONO (2400 1835);
DISPLAY INVISIBLE (2400 1835);
WIRE 16 -1 (2750 1825)(3075 1825);
WIRE 16 -1 (2750 1025)(2750 1825);
WIRE 16 -1 (1825 1025)(2750 1025);
WIRE 16 -1 (1925 1775)(2675 1775);
FORCEPROP 2 LAST SIG_NAME SMB_CPU1_SEC_R_SDA
J 2
(2640 1785);
DISPLAY 0.489362 (2640 1785);
FORCEPROP 2 LASTPROP $XRERR UNIQUE?
J 0
(2400 1785);
DISPLAY 0.638298 (2400 1785);
PAINT MONO (2400 1785);
DISPLAY INVISIBLE (2400 1785);
WIRE 16 -1 (2675 1775)(3075 1775);
WIRE 16 -1 (2675 1100)(2675 1775);
WIRE 16 -1 (1825 1100)(2675 1100);
WIRE 16 -1 (1925 2075)(2500 2075);
FORCEPROP 2 LAST SIG_NAME FM_SEC_MUX_OE_N
J 0
(1990 2085);
DISPLAY 0.680851 (1990 2085);
WIRE 16 -1 (3275 1925)(4000 1925);
FORCEPROP 2 LAST SIG_NAME SMB_CPU0_SEC_SCL
J 2
(3815 1935);
DISPLAY 0.489362 (3815 1935);
WIRE 16 -1 (3275 1875)(4000 1875);
FORCEPROP 2 LAST SIG_NAME SMB_CPU0_SEC_SDA
J 2
(3815 1885);
DISPLAY 0.489362 (3815 1885);
WIRE 16 -1 (1925 2025)(2500 2025);
FORCEPROP 2 LAST SIG_NAME FM_SEC_MUX_SEL
J 0
(1990 2035);
DISPLAY 0.680851 (1990 2035);
WIRE 16 -1 (5050 2375)(6525 2375);
FORCEPROP 2 LAST SIG_NAME SMB_CPU1_SEC_SCL
J 2
(5590 2385);
DISPLAY 0.489362 (5590 2385);
WIRE 16 -1 (6525 2625)(6525 2375);
WIRE 16 -1 (5050 2325)(6850 2325);
FORCEPROP 2 LAST SIG_NAME SMB_CPU1_SEC_SDA
J 2
(5590 2335);
DISPLAY 0.489362 (5590 2335);
WIRE 16 -1 (6850 2625)(6850 2325);
WIRE 16 -1 (5175 3325)(6550 3325);
FORCEPROP 2 LAST SIG_NAME SMB_CPU0_SEC_SCL
J 2
(5690 3335);
DISPLAY 0.489362 (5690 3335);
WIRE 16 -1 (6550 3325)(6550 3550);
WIRE 16 -1 (5175 3275)(6875 3275);
FORCEPROP 2 LAST SIG_NAME SMB_CPU0_SEC_SDA
J 2
(5690 3285);
DISPLAY 0.489362 (5690 3285);
WIRE 16 -1 (6875 3550)(6875 3275);
WIRE 16 -1 (3975 3975)(3250 3975);
FORCEPROP 2 LAST SIG_NAME SMB_APML_CPU0_SCL
J 0
(3490 3985);
DISPLAY 0.489362 (3490 3985);
WIRE 16 -1 (3250 3825)(3975 3825);
FORCEPROP 2 LAST SIG_NAME SMB_APML_CPU1_SDA
J 0
(3490 3835);
DISPLAY 0.489362 (3490 3835);
WIRE 16 -1 (3250 3875)(3975 3875);
FORCEPROP 2 LAST SIG_NAME SMB_APML_CPU1_SCL
J 0
(3490 3885);
DISPLAY 0.489362 (3490 3885);
WIRE 16 -1 (3975 4025)(3250 4025);
FORCEPROP 2 LAST SIG_NAME SMB_APML_CPU0_SDA
J 0
(3490 4035);
DISPLAY 0.489362 (3490 4035);
WIRE 16 -1 (2100 3875)(2650 3875);
FORCEPROP 2 LAST SIG_NAME SMB_APML_CPU1_R_SCL
J 2
(2615 3885);
DISPLAY 0.489362 (2615 3885);
FORCEPROP 2 LASTPROP $XRERR UNIQUE?
J 0
(2375 3885);
DISPLAY 0.638298 (2375 3885);
PAINT MONO (2375 3885);
DISPLAY INVISIBLE (2375 3885);
WIRE 16 -1 (2650 3875)(3050 3875);
WIRE 16 -1 (2650 3875)(2650 3225);
WIRE 16 -1 (1800 3225)(2650 3225);
WIRE 16 -1 (1800 3150)(2725 3150);
WIRE 16 -1 (2725 3825)(2725 3150);
WIRE 16 -1 (2725 3825)(2800 3825);
WIRE 16 -1 (2100 3825)(2725 3825);
FORCEPROP 2 LAST SIG_NAME SMB_APML_CPU1_R_SDA
J 2
(2615 3835);
DISPLAY 0.489362 (2615 3835);
FORCEPROP 2 LASTPROP $XRERR UNIQUE?
J 0
(2375 3835);
DISPLAY 0.638298 (2375 3835);
PAINT MONO (2375 3835);
DISPLAY INVISIBLE (2375 3835);
WIRE 16 -1 (2800 3825)(3050 3825);
WIRE 16 -1 (2800 3825)(2800 3700);
WIRE 16 -1 (1750 4925)(2675 4925);
WIRE 16 -1 (2675 4925)(2675 4025);
WIRE 16 -1 (3050 4025)(2675 4025);
WIRE 16 -1 (2675 4025)(2100 4025);
FORCEPROP 2 LAST SIG_NAME SMB_APML_CPU0_R_SDA
J 2
(2615 4035);
DISPLAY 0.489362 (2615 4035);
FORCEPROP 2 LASTPROP $XRERR UNIQUE?
J 0
(2375 4035);
DISPLAY 0.638298 (2375 4035);
PAINT MONO (2375 4035);
DISPLAY INVISIBLE (2375 4035);
WIRE 16 -1 (2925 5550)(2225 5550);
FORCEPROP 2 LAST SIG_NAME SMB_CPU0_CPU1_APML_SCL_R2
J 0
(2215 5560);
DISPLAY 0.404255 (2215 5560);
PAINT WHITE (2215 5560);
WIRE 16 -1 (7225 5450)(5925 5450);
FORCEPROP 2 LAST SIG_NAME SMB_APML_CPU0_SCL
J 0
(6665 5460);
DISPLAY 0.489362 (6665 5460);
WIRE 16 -1 (4900 5450)(5725 5450);
FORCEPROP 2 LAST SIG_NAME SMB_APML_CPU0_MUX2_SCL
J 0
(4965 5450);
DISPLAY 0.489362 (4965 5450);
FORCEPROP 2 LASTPROP $XRERR UNIQUE?
J 0
(4725 5450);
DISPLAY 0.638298 (4725 5450);
PAINT MONO (4725 5450);
DISPLAY INVISIBLE (4725 5450);
WIRE 16 -1 (5925 5400)(7200 5400);
FORCEPROP 2 LAST SIG_NAME SMB_APML_CPU0_SDA
J 0
(6665 5410);
DISPLAY 0.489362 (6665 5410);
WIRE 16 -1 (7225 5350)(5925 5350);
FORCEPROP 2 LAST SIG_NAME SMB_APML_CPU1_SCL
J 0
(6640 5360);
DISPLAY 0.489362 (6640 5360);
WIRE 16 -1 (4900 5350)(5725 5350);
FORCEPROP 2 LAST SIG_NAME SMB_APML_CPU1_MUX2_SCL
J 0
(4965 5350);
DISPLAY 0.489362 (4965 5350);
FORCEPROP 2 LASTPROP $XRERR UNIQUE?
J 0
(4725 5350);
DISPLAY 0.638298 (4725 5350);
PAINT MONO (4725 5350);
DISPLAY INVISIBLE (4725 5350);
WIRE 16 -1 (5925 5300)(7225 5300);
FORCEPROP 2 LAST SIG_NAME SMB_APML_CPU1_SDA
J 0
(6665 5310);
DISPLAY 0.489362 (6665 5310);
WIRE 16 -1 (4900 5300)(5725 5300);
FORCEPROP 2 LAST SIG_NAME SMB_APML_CPU1_MUX2_SDA
J 0
(4965 5300);
DISPLAY 0.489362 (4965 5300);
FORCEPROP 2 LASTPROP $XRERR UNIQUE?
J 0
(4725 5300);
DISPLAY 0.638298 (4725 5300);
PAINT MONO (4725 5300);
DISPLAY INVISIBLE (4725 5300);
WIRE 16 -1 (4300 5600)(4150 5600);
WIRE 16 -1 (4150 5600)(4150 6125);
WIRE 16 -1 (4150 6150)(4150 6125);
WIRE 16 -1 (3750 6125)(4150 6125);
WIRE 16 -1 (3750 6000)(3750 6125);
WIRE 16 -1 (1150 2600)(1150 2575);
WIRE 16 -1 (1150 2575)(1150 2075);
WIRE 16 -1 (750 2575)(1150 2575);
WIRE 16 -1 (750 2450)(750 2575);
WIRE 16 -1 (1150 2075)(1325 2075);
WIRE 16 -1 (525 4525)(700 4525);
WIRE 16 -1 (700 4525)(875 4525);
WIRE 16 -1 (700 4450)(700 4525);
WIRE 16 -1 (875 4650)(875 4525);
WIRE 16 -1 (875 4525)(875 4125);
WIRE 16 -1 (1250 4125)(875 4125);
WIRE 16 -1 (6225 2925)(6225 2825);
WIRE 16 -1 (6225 3000)(6225 2925);
WIRE 16 -1 (5900 2925)(6225 2925);
WIRE 16 -1 (5900 2925)(5900 2825);
WIRE 16 -1 (6250 3925)(6250 3850);
WIRE 16 -1 (6250 3850)(6250 3750);
WIRE 16 -1 (5925 3850)(6250 3850);
WIRE 16 -1 (5925 3850)(5925 3750);
WIRE 16 -1 (6875 3925)(6875 3850);
WIRE 16 -1 (6875 3850)(6875 3750);
WIRE 16 -1 (6550 3850)(6875 3850);
WIRE 16 -1 (6550 3850)(6550 3750);
WIRE 16 -1 (6525 2925)(6850 2925);
WIRE 16 -1 (6525 2925)(6525 2825);
WIRE 16 -1 (6850 3000)(6850 2925);
WIRE 16 -1 (6850 2925)(6850 2825);
DOT 1 (700 4525);
DOT 1 (-150 3825);
DOT 1 (2725 3825);
DOT 1 (2650 3875);
DOT 1 (875 4525);
DOT 1 (2800 3825);
DOT 1 (2725 3975);
DOT 1 (2675 4025);
DOT 1 (775 3825);
DOT 1 (725 3875);
CIRCLE (2275 2400)(2416 2400);
PAINT YELLOW (2275 2400);
DOT 1 (4150 6125);
DOT 1 (6850 2925);
DOT 1 (6875 3850);
DOT 1 (2900 1925);
DOT 1 (2950 1875);
DOT 1 (2675 1775);
DOT 1 (2750 1825);
DOT 1 (250 4525);
DOT 1 (6225 2925);
DOT 1 (6250 3850);
DOT 1 (-75 2025);
DOT 1 (-25 2025);
DOT 1 (25 1975);
DOT 1 (-150 1975);
DOT 1 (1150 2575);
CIRCLE (6325 6075)(6540 6075);
PAINT YELLOW (6325 6075);
DOT 1 (-75 3875);
FORCENOTE
U4 IS APML MUX 2ND SOURCE
(2850 5000) 0;
DISPLAY LEFT (2850 5000);
DISPLAY 1.595745 (2850 5000);
FORCENOTE
U213 IS APML MUX MAIN SOURCE
(2800 4200) 0;
DISPLAY LEFT (2800 4200);
DISPLAY 1.595745 (2800 4200);
FORCENOTE
ADDR:0XE0(8-BIT)/0X70(7-BIT)
(1000 3475) 0;
DISPLAY LEFT (1000 3475);
DISPLAY 1.021277 (1000 3475);
PAINT SKYBLUE (1000 3475);
FORCENOTE
TBC
(2200 2375) 0;
DISPLAY LEFT (2200 2375);
DISPLAY 1.021277 (2200 2375);
FORCENOTE
TBC
(6225 6025) 0;
DISPLAY LEFT (6225 6025);
DISPLAY 1.595745 (6225 6025);
QUIT
